G04 ================== begin FILE IDENTIFICATION RECORD ==================*
G04 Layout Name:  9049_F0T_FAN_BOARD_MP5048_D_v02_20221209_0830.brd*
G04 Film Name:    panel*
G04 File Format:  Gerber RS274X*
G04 File Origin:  Cadence Allegro 17.2-S081*
G04 Origin Date:  Mon Dec 12 15:05:04 2022*
G04 *
G04 Layer:  DRAWING FORMAT/TITLE_BLOCK_A*
G04 Layer:  MANUFACTURING/PHOTOPLOT_OUTLINE*
G04 Layer:  DRAWING FORMAT/TITLE_BLOCK*
G04 Layer:  DRAWING FORMAT/TITLE_DATA_PANEL*
G04 Layer:  BOARD GEOMETRY/ASSEMBLY_NOTES*
G04 *
G04 Offset:    (0.00 0.00)*
G04 Mirror:    No*
G04 Mode:      Positive*
G04 Rotation:  0*
G04 FullContactRelief:  No*
G04 UndefLineWidth:     6.00*
G04 ================== end FILE IDENTIFICATION RECORD ====================*
%FSLAX25Y25*MOIN*%
%IR0*IPPOS*OFA0.00000B0.00000*MIA0B0*SFA1.00000B1.00000*%
%ADD10C,.1*%
%ADD11C,.006*%
G75*
%LPD*%
G75*
G36*
G01X-56221Y1279528D02*
G02I-1968J0D01*
G37*
G36*
G01X867322Y66929D02*
G02I-1969J0D01*
G37*
G36*
G01X1271882Y134110D02*
G02I-1969J0D01*
G37*
G54D10*
G01X153000Y716000D02*
X67000D01*
Y608000D01*
G01Y662000D02*
X142000D01*
G01X278417Y716000D02*
Y608000D01*
G01Y662000D02*
X353417D01*
G01X364417Y716000D02*
X278417D01*
G01X489834D02*
Y608000D01*
G01Y662000D02*
X564834D01*
G01X575834Y716000D02*
X489834D01*
G01X701251D02*
Y608000D01*
G01Y662000D02*
X776251D01*
G01X787251Y716000D02*
X701251D01*
G54D11*
G01X-320500Y-470483D02*
Y2626000D01*
X2967000D01*
Y-470483D01*
X-320500D01*
G01X-76641Y1323129D02*
X-184897Y1326609D01*
G01X-87717Y0D02*
X-173189D01*
G01X-173608Y1339053D02*
X-173367Y1346549D01*
X-171035Y1346474D01*
X-170301Y1346075D01*
X-169850Y1345561D01*
X-169696Y1344555D01*
X-169915Y1343562D01*
X-170495Y1342955D01*
X-171160Y1342601D01*
X-173492Y1342676D01*
G01X-171160Y1342601D02*
X-169877Y1338933D01*
G01X-165818Y1345056D02*
X-165234Y1345787D01*
X-164569Y1346141D01*
X-163819Y1346242D01*
X-162894Y1345962D01*
X-162261Y1345317D01*
X-162099Y1344561D01*
X-162216Y1343814D01*
X-162609Y1343202D01*
X-164515Y1342012D01*
X-165383Y1341165D01*
X-165983Y1339933D01*
X-166205Y1338815D01*
X-162287Y1338689D01*
G01X-159549Y1338601D02*
X-159388Y1343598D01*
G01X-159433Y1342224D02*
X-159133Y1342840D01*
X-158650Y1343324D01*
X-157989Y1343553D01*
X-157344Y1343282D01*
X-156894Y1342768D01*
X-156634Y1342134D01*
X-156751Y1338511D01*
G01X-156634Y1342134D02*
X-156334Y1342750D01*
X-155852Y1343235D01*
X-155191Y1343463D01*
X-154546Y1343193D01*
X-154095Y1342678D01*
X-153839Y1341919D01*
X-153952Y1338421D01*
G01X-152053Y1338360D02*
X-151892Y1343357D01*
G01X-151937Y1341983D02*
X-151637Y1342599D01*
X-151154Y1343083D01*
X-150493Y1343312D01*
X-149848Y1343041D01*
X-149398Y1342527D01*
X-149138Y1341893D01*
X-149255Y1338270D01*
G01X-149138Y1341893D02*
X-148838Y1342509D01*
X-148356Y1342994D01*
X-147695Y1343222D01*
X-147050Y1342952D01*
X-146599Y1342437D01*
X-146343Y1341678D01*
X-146456Y1338180D01*
G01X-92460Y1321176D02*
X-76641Y1323129D01*
X-92302Y1326095D01*
X-92460Y1321176D01*
G01X-77874Y-9843D02*
Y-80079D01*
G01X-7874Y54252D02*
Y7874D01*
G02X-15748Y0I-7874J0D01*
G01X-70000D01*
G02X-77874Y7874I0J7874D01*
G01Y54252D01*
G01D02*
Y584252D01*
X-7874D01*
Y54252D01*
G01X-77874D02*
X-7874D01*
G01Y519252D02*
X-77874D01*
G01Y584252D02*
G02X-70000Y592126I7874J0D01*
G01X-15748D01*
G02X-7874Y584252I0J-7874D01*
G01X-62559Y592126D02*
G03Y600000I0J3937D01*
G01X-70000D02*
X-15748D01*
G03X-7874Y607874I0J7874D01*
G01Y1318898D01*
G03X-15748Y1326772I-7874J0D01*
G01X-70000D01*
G03X-77874Y1318898I0J-7874D01*
G01Y607874D01*
G03X-70000Y600000I7874J0D01*
G01X-46378D02*
X-70000D01*
G01X-77874Y1204829D02*
Y1440000D01*
G01Y1265772D02*
Y1318898D01*
G02X-70000Y1326772I7874J0D01*
G01D02*
X-46378D01*
G01X371675Y1439000D02*
X-77874D01*
G01X-72874Y1440000D02*
X-77874Y1439000D01*
X-72874Y1438000D01*
Y1440000D01*
G01X-38504Y-2990D02*
Y-39390D01*
G01X-37362Y598819D02*
G03I-1575J0D01*
G01X-53110D02*
G03I-1575J0D01*
G01X-45236D02*
G03I-1575J0D01*
G01X-23189Y592126D02*
G02Y600000I0J3937D01*
G01X-29488Y598819D02*
G03I-1575J0D01*
G01X0Y1311024D02*
Y15748D01*
G01D02*
G03X15748Y0I15748J0D01*
G01X0Y187035D02*
G03X-7874I-3937J0D01*
G01X0Y206721D02*
G02X-7874I-3937J0D01*
G01Y309409D02*
G02X0I3937J0D01*
G01X-7874Y329095D02*
G03X0I3937J0D01*
G01X-7874Y572441D02*
G03X0I3937J0D01*
G01X-7874Y552755D02*
G02X0I3937J0D01*
G01X-7874Y713566D02*
G03X0I3937J0D01*
G01X-7874Y693880D02*
G02X0I3937J0D01*
G01Y914527D02*
G03X-7874I-3937J0D01*
G01X0Y934213D02*
G02X-7874I-3937J0D01*
G01X0Y1029527D02*
G03X-7874I-3937J0D01*
G01X0Y1049213D02*
G02X-7874I-3937J0D01*
G01Y1277559D02*
G02X0I3937J0D01*
G01X-7874D02*
G02X0I3937J0D01*
G01X-7874Y1297244D02*
G03X0I3937J0D01*
G01X-7874D02*
G03X0I3937J0D01*
G01Y1311024D02*
G02X15748Y1326772I15748J0D01*
G01X187795D01*
G02X203543Y1311024I0J-15748D01*
G01X15748Y0D02*
X58898D01*
G01D02*
X64803Y5906D01*
G01D02*
Y43307D01*
G01X74252D02*
Y7283D01*
G01D02*
X80157Y1378D01*
G01X64803Y43307D02*
G02X74252I4724J0D01*
G01X80157Y1378D02*
X99488D01*
G01D02*
X105394Y7283D01*
G01D02*
Y43307D01*
G01X108150D02*
Y7283D01*
G01D02*
X114055Y1378D01*
G01D02*
X123386D01*
G01D02*
X129291Y7283D01*
G01X105394Y43307D02*
G02X108150I1378J0D01*
G01X138740Y5906D02*
X144646Y0D01*
G01D02*
X187795D01*
G01X138740Y43307D02*
Y5906D01*
G01X129291Y7283D02*
Y43307D01*
G01D02*
G02X138740I4724J0D01*
G01X187795Y0D02*
G03X203543Y15748I0J15748D01*
G01D02*
Y1311024D01*
G01X211417Y15748D02*
G03X227165Y0I15748J0D01*
G01X211417Y1311024D02*
Y15748D01*
G01Y187035D02*
G03X203543I-3937J0D01*
G01X211417Y206721D02*
G02X203543I-3937J0D01*
G01Y309409D02*
G02X211417I3937J0D01*
G01X203543Y329095D02*
G03X211417I3937J0D01*
G01X203543Y552755D02*
G02X211417I3937J0D01*
G01X203543Y572441D02*
G03X211417I3937J0D01*
G01X203543Y693880D02*
G02X211417I3937J0D01*
G01X203543Y713566D02*
G03X211417I3937J0D01*
G01Y914527D02*
G03X203543I-3937J0D01*
G01X211417Y934213D02*
G02X203543I-3937J0D01*
G01X211417Y1029527D02*
G03X203543I-3937J0D01*
G01X211417Y1049213D02*
G02X203543I-3937J0D01*
G01Y1277559D02*
G02X211417I3937J0D01*
G01X203543D02*
G02X211417I3937J0D01*
G01X203543Y1297244D02*
G03X211417I3937J0D01*
G01X203543D02*
G03X211417I3937J0D01*
G01X227165Y1326772D02*
G03X211417Y1311024I0J-15748D01*
G01X227165Y0D02*
X270315D01*
G01X399212Y1326772D02*
X227165D01*
G01X276220Y5906D02*
Y43307D01*
G01X270315Y0D02*
X276220Y5906D01*
G01Y43307D02*
G02X285669I4725J0D01*
G01D02*
Y7283D01*
G01D02*
X291574Y1378D01*
G01D02*
X310905D01*
G01X329322Y-314459D02*
Y-319459D01*
G01X327865Y-314459D02*
X330779D01*
G01X335689Y-319459D02*
X333155D01*
Y-314459D01*
X335689D01*
G01X334675Y-316876D02*
X333155D01*
G01X338255Y-314459D02*
Y-319459D01*
X340789D01*
G01X344622Y-319626D02*
X344495Y-319542D01*
Y-319376D01*
X344622Y-319292D01*
X344749Y-319376D01*
Y-319542D01*
X344622Y-319626D01*
G01Y-317376D02*
X344495Y-317292D01*
Y-317126D01*
X344622Y-317042D01*
X344749Y-317126D01*
Y-317292D01*
X344622Y-317376D01*
G01X349405Y-321126D02*
X348772Y-320292D01*
X348455Y-319459D01*
Y-316126D01*
X348772Y-315292D01*
X349405Y-314459D01*
G01X354822D02*
X354315Y-314626D01*
X353935Y-315042D01*
X353682Y-315542D01*
X353492Y-316209D01*
X353429Y-316959D01*
X353492Y-317709D01*
X353682Y-318376D01*
X353935Y-318876D01*
X354315Y-319292D01*
X354822Y-319459D01*
X355329Y-319292D01*
X355709Y-318876D01*
X355962Y-318376D01*
X356152Y-317709D01*
X356215Y-316959D01*
X356152Y-316209D01*
X355962Y-315542D01*
X355709Y-315042D01*
X355329Y-314626D01*
X354822Y-314459D01*
G01X358529Y-318459D02*
X358909Y-319042D01*
X359415Y-319376D01*
X359985Y-319459D01*
X360492Y-319376D01*
X360999Y-318959D01*
X361315Y-318459D01*
X361379Y-317959D01*
X361252Y-317376D01*
X360809Y-316959D01*
X360365Y-316792D01*
X359795D01*
G01X360365D02*
X360745Y-316542D01*
X361062Y-316126D01*
X361189Y-315626D01*
X361062Y-315126D01*
X360745Y-314709D01*
X360175Y-314459D01*
X359605Y-314542D01*
X359035Y-314876D01*
G01X365339Y-321126D02*
X365972Y-320292D01*
X366289Y-319459D01*
Y-316126D01*
X365972Y-315292D01*
X365339Y-314459D01*
G01X368729Y-318459D02*
X369109Y-319042D01*
X369615Y-319376D01*
X370185Y-319459D01*
X370692Y-319376D01*
X371199Y-318959D01*
X371515Y-318459D01*
X371579Y-317959D01*
X371452Y-317376D01*
X371009Y-316959D01*
X370565Y-316792D01*
X369995D01*
G01X370565D02*
X370945Y-316542D01*
X371262Y-316126D01*
X371389Y-315626D01*
X371262Y-315126D01*
X370945Y-314709D01*
X370375Y-314459D01*
X369805Y-314542D01*
X369235Y-314876D01*
G01X374019Y-315292D02*
X374399Y-314792D01*
X374842Y-314542D01*
X375349Y-314459D01*
X375982Y-314626D01*
X376425Y-315042D01*
X376552Y-315542D01*
X376489Y-316042D01*
X376235Y-316459D01*
X374969Y-317292D01*
X374399Y-317876D01*
X374019Y-318709D01*
X373892Y-319459D01*
X376552D01*
G01X380195D02*
X380322Y-318376D01*
X380512Y-317459D01*
X380765Y-316626D01*
X381082Y-315709D01*
X381589Y-314459D01*
X379055D01*
G01X384599Y-317792D02*
X386245D01*
G01X389319Y-315292D02*
X389699Y-314792D01*
X390142Y-314542D01*
X390649Y-314459D01*
X391282Y-314626D01*
X391725Y-315042D01*
X391852Y-315542D01*
X391789Y-316042D01*
X391535Y-316459D01*
X390269Y-317292D01*
X389699Y-317876D01*
X389319Y-318709D01*
X389192Y-319459D01*
X391852D01*
G01X394229Y-318459D02*
X394609Y-319042D01*
X395115Y-319376D01*
X395685Y-319459D01*
X396192Y-319376D01*
X396699Y-318959D01*
X397015Y-318459D01*
X397079Y-317959D01*
X396952Y-317376D01*
X396509Y-316959D01*
X396065Y-316792D01*
X395495D01*
G01X396065D02*
X396445Y-316542D01*
X396762Y-316126D01*
X396889Y-315626D01*
X396762Y-315126D01*
X396445Y-314709D01*
X395875Y-314459D01*
X395305Y-314542D01*
X394735Y-314876D01*
G01X401482Y-319459D02*
Y-314459D01*
X399139Y-318042D01*
X402305D01*
G01X404429Y-318709D02*
X404809Y-319126D01*
X405252Y-319376D01*
X405822Y-319459D01*
X406392Y-319292D01*
X406835Y-318959D01*
X407152Y-318376D01*
X407215Y-317709D01*
X407089Y-317042D01*
X406772Y-316626D01*
X406329Y-316292D01*
X405885Y-316209D01*
X405442Y-316292D01*
X404872Y-316626D01*
X405062Y-314459D01*
X406772D01*
G01X414819Y-319459D02*
Y-314459D01*
X417225D01*
G01X416339Y-316876D02*
X414819D01*
G01X419539Y-319459D02*
X421122Y-314459D01*
X422705Y-319459D01*
G01X422135Y-317709D02*
X420109D01*
G01X424892Y-319459D02*
X427552Y-314459D01*
G01X424892D02*
X427552Y-319459D01*
G01X431322Y-319626D02*
X431195Y-319542D01*
Y-319376D01*
X431322Y-319292D01*
X431449Y-319376D01*
Y-319542D01*
X431322Y-319626D01*
G01Y-317376D02*
X431195Y-317292D01*
Y-317126D01*
X431322Y-317042D01*
X431449Y-317126D01*
Y-317292D01*
X431322Y-317376D01*
G01X436105Y-321126D02*
X435472Y-320292D01*
X435155Y-319459D01*
Y-316126D01*
X435472Y-315292D01*
X436105Y-314459D01*
G01X441522D02*
X441015Y-314626D01*
X440635Y-315042D01*
X440382Y-315542D01*
X440192Y-316209D01*
X440129Y-316959D01*
X440192Y-317709D01*
X440382Y-318376D01*
X440635Y-318876D01*
X441015Y-319292D01*
X441522Y-319459D01*
X442029Y-319292D01*
X442409Y-318876D01*
X442662Y-318376D01*
X442852Y-317709D01*
X442915Y-316959D01*
X442852Y-316209D01*
X442662Y-315542D01*
X442409Y-315042D01*
X442029Y-314626D01*
X441522Y-314459D01*
G01X445229Y-318459D02*
X445609Y-319042D01*
X446115Y-319376D01*
X446685Y-319459D01*
X447192Y-319376D01*
X447699Y-318959D01*
X448015Y-318459D01*
X448079Y-317959D01*
X447952Y-317376D01*
X447509Y-316959D01*
X447065Y-316792D01*
X446495D01*
G01X447065D02*
X447445Y-316542D01*
X447762Y-316126D01*
X447889Y-315626D01*
X447762Y-315126D01*
X447445Y-314709D01*
X446875Y-314459D01*
X446305Y-314542D01*
X445735Y-314876D01*
G01X452039Y-321126D02*
X452672Y-320292D01*
X452989Y-319459D01*
Y-316126D01*
X452672Y-315292D01*
X452039Y-314459D01*
G01X455429Y-318459D02*
X455809Y-319042D01*
X456315Y-319376D01*
X456885Y-319459D01*
X457392Y-319376D01*
X457899Y-318959D01*
X458215Y-318459D01*
X458279Y-317959D01*
X458152Y-317376D01*
X457709Y-316959D01*
X457265Y-316792D01*
X456695D01*
G01X457265D02*
X457645Y-316542D01*
X457962Y-316126D01*
X458089Y-315626D01*
X457962Y-315126D01*
X457645Y-314709D01*
X457075Y-314459D01*
X456505Y-314542D01*
X455935Y-314876D01*
G01X460845Y-318876D02*
X461289Y-319292D01*
X461795Y-319459D01*
X462302Y-319292D01*
X462745Y-318792D01*
X463062Y-318042D01*
X463189Y-317292D01*
Y-316376D01*
X463062Y-315626D01*
X462745Y-314959D01*
X462365Y-314626D01*
X461922Y-314459D01*
X461415Y-314626D01*
X461035Y-314959D01*
X460782Y-315459D01*
X460655Y-316126D01*
X460782Y-316709D01*
X461099Y-317292D01*
X461479Y-317626D01*
X461922Y-317709D01*
X462429Y-317542D01*
X462809Y-317126D01*
X463189Y-316376D01*
G01X466895Y-319459D02*
X467022Y-318376D01*
X467212Y-317459D01*
X467465Y-316626D01*
X467782Y-315709D01*
X468289Y-314459D01*
X465755D01*
G01X471299Y-317792D02*
X472945D01*
G01X475829Y-318459D02*
X476209Y-319042D01*
X476715Y-319376D01*
X477285Y-319459D01*
X477792Y-319376D01*
X478299Y-318959D01*
X478615Y-318459D01*
X478679Y-317959D01*
X478552Y-317376D01*
X478109Y-316959D01*
X477665Y-316792D01*
X477095D01*
G01X477665D02*
X478045Y-316542D01*
X478362Y-316126D01*
X478489Y-315626D01*
X478362Y-315126D01*
X478045Y-314709D01*
X477475Y-314459D01*
X476905Y-314542D01*
X476335Y-314876D01*
G01X481119Y-317376D02*
X481562Y-316792D01*
X481942Y-316459D01*
X482449Y-316292D01*
X482892Y-316459D01*
X483209Y-316792D01*
X483462Y-317292D01*
X483525Y-317876D01*
X483462Y-318376D01*
X483209Y-318876D01*
X482829Y-319292D01*
X482385Y-319459D01*
X481879Y-319292D01*
X481435Y-318792D01*
X481182Y-318042D01*
X481119Y-317209D01*
X481245Y-316126D01*
X481435Y-315542D01*
X481752Y-314959D01*
X482195Y-314542D01*
X482639Y-314459D01*
X483082Y-314626D01*
X483399Y-315042D01*
G01X487422Y-319459D02*
Y-314459D01*
X486662Y-315459D01*
G01Y-319459D02*
X488182D01*
G01X493282D02*
Y-314459D01*
X490939Y-318042D01*
X494105D01*
G01X317322Y-249459D02*
Y-324459D01*
X817322D01*
Y-249459D01*
X317322D01*
G01X310905Y1378D02*
X316811Y7283D01*
G01D02*
Y43307D01*
G01X319567D02*
Y7283D01*
G01D02*
X325472Y1378D01*
G01D02*
X334803D01*
G01X316811Y43307D02*
G02X319567I1378J0D01*
G01X350157D02*
Y5906D01*
G01D02*
X356063Y0D01*
G01X334803Y1378D02*
X340708Y7283D01*
G01D02*
Y43307D01*
G01D02*
G02X350157I4724J0D01*
G01X356063Y0D02*
X399212D01*
G01D02*
G03X414960Y15748I0J15748D01*
G01Y1311024D02*
G03X399212Y1326772I-15748J0D01*
G01X385700Y1420250D02*
X381050D01*
Y1432750D01*
X385700D01*
G01X414960Y15748D02*
Y1311024D01*
G01X422834Y15748D02*
G03X438582Y0I15748J0D01*
G01X422834Y1311024D02*
Y15748D01*
G01Y187035D02*
G03X414960I-3937J0D01*
G01X422834Y206721D02*
G02X414960I-3937J0D01*
G01Y309409D02*
G02X422834I3937J0D01*
G01X414960Y329095D02*
G03X422834I3937J0D01*
G01X414960Y552755D02*
G02X422834I3937J0D01*
G01X414960Y572441D02*
G03X422834I3937J0D01*
G01X414960Y713566D02*
G03X422834I3937J0D01*
G01X414960Y693880D02*
G02X422834I3937J0D01*
G01Y914527D02*
G03X414960I-3937J0D01*
G01X422834Y934213D02*
G02X414960I-3937J0D01*
G01X422834Y1029527D02*
G03X414960I-3937J0D01*
G01X422834Y1049213D02*
G02X414960I-3937J0D01*
G01Y1277559D02*
G02X422834I3937J0D01*
G01X414960D02*
G02X422834I3937J0D01*
G01X414960Y1297244D02*
G03X422834I3937J0D01*
G01X414960D02*
G03X422834I3937J0D01*
G01X438582Y1326772D02*
G03X422834Y1311024I0J-15748D01*
G01X438582Y0D02*
X481732D01*
G01X610629Y1326772D02*
X438582D01*
G01X466300Y1420250D02*
X470950D01*
Y1432750D01*
X466300D01*
G01X487637Y5906D02*
Y43307D01*
G01X481732Y0D02*
X487637Y5906D01*
G01Y43307D02*
G02X497086I4725J0D01*
G01X480325Y1439000D02*
X885038D01*
G01X512322Y-249459D02*
Y-324459D01*
G01Y-299459D02*
X615322D01*
Y-274459D01*
G01X512322D02*
X615322D01*
G01X497086Y43307D02*
Y7283D01*
G01D02*
X502991Y1378D01*
G01D02*
X522322D01*
G01D02*
X528228Y7283D01*
G01D02*
Y43307D01*
G01X530984D02*
Y7283D01*
G01D02*
X536889Y1378D01*
G01D02*
X546220D01*
G01X528228Y43307D02*
G02X530984I1378J0D01*
G01X561574D02*
Y5906D01*
G01D02*
X567480Y0D01*
G01X546220Y1378D02*
X552125Y7283D01*
G01D02*
Y43307D01*
G01D02*
G02X561574I4725J0D01*
G01X567480Y0D02*
X610629D01*
G01X622829Y-309459D02*
Y-304459D01*
X624095D01*
X624602Y-304709D01*
X624982Y-305042D01*
X625299Y-305542D01*
X625552Y-306126D01*
X625615Y-306959D01*
X625552Y-307792D01*
X625299Y-308376D01*
X624982Y-308876D01*
X624602Y-309209D01*
X624095Y-309459D01*
X622829D01*
G01X627739D02*
X629322Y-304459D01*
X630905Y-309459D01*
G01X630335Y-307709D02*
X628309D01*
G01X634422Y-304459D02*
Y-309459D01*
G01X632965Y-304459D02*
X635879D01*
G01X640789Y-309459D02*
X638255D01*
Y-304459D01*
X640789D01*
G01X639775Y-306876D02*
X638255D01*
G01X644622Y-309626D02*
X644495Y-309542D01*
Y-309376D01*
X644622Y-309292D01*
X644749Y-309376D01*
Y-309542D01*
X644622Y-309626D01*
G01Y-307376D02*
X644495Y-307292D01*
Y-307126D01*
X644622Y-307042D01*
X644749Y-307126D01*
Y-307292D01*
X644622Y-307376D01*
G01X617322Y-249459D02*
Y-324459D01*
G01X615322Y-249459D02*
Y-324459D01*
G01X622955Y-284459D02*
Y-279459D01*
X624475D01*
X624982Y-279709D01*
X625362Y-280292D01*
X625489Y-280959D01*
X625362Y-281626D01*
X625045Y-282126D01*
X624475Y-282376D01*
X622955D01*
G01X628182Y-284626D02*
X630462Y-279459D01*
G01X632965Y-284459D02*
Y-279459D01*
X635879Y-284459D01*
Y-279459D01*
G01X639522Y-284626D02*
X639395Y-284542D01*
Y-284376D01*
X639522Y-284292D01*
X639649Y-284376D01*
Y-284542D01*
X639522Y-284626D01*
G01Y-282376D02*
X639395Y-282292D01*
Y-282126D01*
X639522Y-282042D01*
X639649Y-282126D01*
Y-282292D01*
X639522Y-282376D01*
G01X617322Y-299459D02*
X817322D01*
G01X622955Y-259459D02*
Y-254459D01*
X624475D01*
X624982Y-254709D01*
X625362Y-255292D01*
X625489Y-255959D01*
X625362Y-256626D01*
X625045Y-257126D01*
X624475Y-257376D01*
X622955D01*
G01X628055Y-259459D02*
Y-254459D01*
X629639D01*
X630145Y-254709D01*
X630462Y-255042D01*
X630589Y-255709D01*
X630462Y-256376D01*
X630082Y-256792D01*
X629639Y-257042D01*
X628055D01*
G01X629639D02*
X630589Y-259459D01*
G01X634422D02*
X633915Y-259376D01*
X633472Y-259042D01*
X633092Y-258542D01*
X632839Y-257959D01*
X632712Y-257292D01*
Y-256626D01*
X632839Y-255959D01*
X633092Y-255376D01*
X633472Y-254876D01*
X633915Y-254542D01*
X634422Y-254459D01*
X634929Y-254542D01*
X635372Y-254876D01*
X635752Y-255376D01*
X636005Y-255959D01*
X636132Y-256626D01*
Y-257292D01*
X636005Y-257959D01*
X635752Y-258542D01*
X635372Y-259042D01*
X634929Y-259376D01*
X634422Y-259459D01*
G01X638255Y-258459D02*
X638572Y-258959D01*
X638952Y-259292D01*
X639395Y-259459D01*
X639902Y-259292D01*
X640282Y-258959D01*
X640662Y-258459D01*
X640789Y-257792D01*
Y-254459D01*
G01X645889Y-259459D02*
X643355D01*
Y-254459D01*
X645889D01*
G01X644875Y-256876D02*
X643355D01*
G01X651115Y-254876D02*
X650735Y-254626D01*
X650292Y-254459D01*
X649785D01*
X649215Y-254709D01*
X648772Y-255126D01*
X648455Y-255626D01*
X648202Y-256459D01*
X648139Y-257209D01*
X648265Y-257959D01*
X648455Y-258459D01*
X648835Y-258959D01*
X649279Y-259292D01*
X649722Y-259459D01*
X650165D01*
X650609Y-259292D01*
X650989Y-259042D01*
X651305Y-258709D01*
G01X654822Y-254459D02*
Y-259459D01*
G01X653365Y-254459D02*
X656279D01*
G01X659922Y-259626D02*
X659795Y-259542D01*
Y-259376D01*
X659922Y-259292D01*
X660049Y-259376D01*
Y-259542D01*
X659922Y-259626D01*
G01Y-257376D02*
X659795Y-257292D01*
Y-257126D01*
X659922Y-257042D01*
X660049Y-257126D01*
Y-257292D01*
X659922Y-257376D01*
G01X617322Y-274459D02*
X817322D01*
G01X610629Y0D02*
G03X626377Y15748I0J15748D01*
G01D02*
Y1311024D01*
G01X634251Y187035D02*
G03X626377I-3937J0D01*
G01X634251Y206721D02*
G02X626377I-3937J0D01*
G01Y309409D02*
G02X634251I3937J0D01*
G01X626377Y329095D02*
G03X634251I3937J0D01*
G01X626377Y552755D02*
G02X634251I3937J0D01*
G01X626377Y572441D02*
G03X634251I3937J0D01*
G01X626377Y713566D02*
G03X634251I3937J0D01*
G01X626377Y693880D02*
G02X634251I3937J0D01*
G01Y914527D02*
G03X626377I-3937J0D01*
G01X634251Y934213D02*
G02X626377I-3937J0D01*
G01X634251Y1029527D02*
G03X626377I-3937J0D01*
G01X634251Y1049213D02*
G02X626377I-3937J0D01*
G01Y1277559D02*
G02X634251I3937J0D01*
G01X626377D02*
G02X634251I3937J0D01*
G01X626377Y1297244D02*
G03X634251I3937J0D01*
G01X626377D02*
G03X634251I3937J0D01*
G01X626377Y1311024D02*
G03X610629Y1326772I-15748J0D01*
G01X634251Y15748D02*
G03X649999Y0I15748J0D01*
G01X634251Y1311024D02*
Y15748D01*
G01X649999Y0D02*
X693149D01*
G01X649999Y1326772D02*
G03X634251Y1311024I0J-15748D01*
G01X822046Y1326772D02*
X649999D01*
G01X699054Y5906D02*
Y43307D01*
G01X693149Y0D02*
X699054Y5906D01*
G01Y43307D02*
G02X708503I4725J0D01*
G01D02*
Y7283D01*
G01D02*
X714408Y1378D01*
G01D02*
X733739D01*
G01X734955Y-301959D02*
Y-306959D01*
X737489D01*
G01X740562Y-301959D02*
X742082D01*
G01X741322D02*
Y-306959D01*
G01X740562D02*
X742082D01*
G01X746929Y-304292D02*
X747182Y-304042D01*
X747372Y-303626D01*
X747499Y-303042D01*
X747372Y-302542D01*
X747119Y-302209D01*
X746675Y-301959D01*
X744965D01*
Y-306959D01*
X747055D01*
X747499Y-306626D01*
X747752Y-306126D01*
X747879Y-305542D01*
X747752Y-304959D01*
X747372Y-304459D01*
X746929Y-304292D01*
X744965D01*
G01X751522Y-307126D02*
X751395Y-307042D01*
Y-306876D01*
X751522Y-306792D01*
X751649Y-306876D01*
Y-307042D01*
X751522Y-307126D01*
G01Y-304876D02*
X751395Y-304792D01*
Y-304626D01*
X751522Y-304542D01*
X751649Y-304626D01*
Y-304792D01*
X751522Y-304876D01*
G01X732322Y-299459D02*
Y-324459D01*
G01X733739Y1378D02*
X739645Y7283D01*
G01D02*
Y43307D01*
G01X742401D02*
Y7283D01*
G01D02*
X748306Y1378D01*
G01X739645Y43307D02*
G02X742401I1378J0D01*
G01X748306Y1378D02*
X757637D01*
G01D02*
X763542Y7283D01*
G01D02*
Y43307D01*
G01D02*
G02X772991I4725J0D01*
G01X779222Y-301959D02*
Y-306959D01*
G01X777765Y-301959D02*
X780679D01*
G01X784322Y-306959D02*
X783942Y-306876D01*
X783562Y-306542D01*
X783309Y-305959D01*
X783182Y-305292D01*
X783309Y-304626D01*
X783562Y-304042D01*
X783942Y-303709D01*
X784322Y-303626D01*
X784702Y-303709D01*
X785082Y-304042D01*
X785335Y-304626D01*
X785399Y-305292D01*
X785335Y-305959D01*
X785082Y-306542D01*
X784702Y-306876D01*
X784322Y-306959D01*
G01X789422D02*
X789042Y-306876D01*
X788662Y-306542D01*
X788409Y-305959D01*
X788282Y-305292D01*
X788409Y-304626D01*
X788662Y-304042D01*
X789042Y-303709D01*
X789422Y-303626D01*
X789802Y-303709D01*
X790182Y-304042D01*
X790435Y-304626D01*
X790499Y-305292D01*
X790435Y-305959D01*
X790182Y-306542D01*
X789802Y-306876D01*
X789422Y-306959D01*
G01X794522D02*
Y-301959D01*
G01X799622Y-307126D02*
X799495Y-307042D01*
Y-306876D01*
X799622Y-306792D01*
X799749Y-306876D01*
Y-307042D01*
X799622Y-307126D01*
G01Y-304876D02*
X799495Y-304792D01*
Y-304626D01*
X799622Y-304542D01*
X799749Y-304626D01*
Y-304792D01*
X799622Y-304876D01*
G01X775322Y-299459D02*
Y-324459D01*
G01Y-274459D02*
Y-299459D01*
G01X777955Y-281959D02*
Y-276959D01*
X779539D01*
X780045Y-277209D01*
X780362Y-277542D01*
X780489Y-278209D01*
X780362Y-278876D01*
X779982Y-279292D01*
X779539Y-279542D01*
X777955D01*
G01X779539D02*
X780489Y-281959D01*
G01X785589D02*
X783055D01*
Y-276959D01*
X785589D01*
G01X784575Y-279376D02*
X783055D01*
G01X787839Y-276959D02*
X789422Y-281959D01*
X791005Y-276959D01*
G01X794522Y-282126D02*
X794395Y-282042D01*
Y-281876D01*
X794522Y-281792D01*
X794649Y-281876D01*
Y-282042D01*
X794522Y-282126D01*
G01Y-279876D02*
X794395Y-279792D01*
Y-279626D01*
X794522Y-279542D01*
X794649Y-279626D01*
Y-279792D01*
X794522Y-279876D01*
G01X772991Y43307D02*
Y5906D01*
G01X778897Y0D02*
X822046D01*
G01X772991Y5906D02*
X778897Y0D01*
G01X798082Y-326159D02*
X798162Y-326084D01*
X798222Y-325959D01*
X798262Y-325784D01*
X798222Y-325634D01*
X798142Y-325534D01*
X798002Y-325459D01*
X797462D01*
Y-326959D01*
X798122D01*
X798262Y-326859D01*
X798342Y-326709D01*
X798382Y-326534D01*
X798342Y-326359D01*
X798222Y-326209D01*
X798082Y-326159D01*
X797462D01*
G01X799482Y-326959D02*
Y-325959D01*
G01Y-326134D02*
X799402Y-326034D01*
X799282Y-325984D01*
X799142Y-325959D01*
X799002Y-326009D01*
X798882Y-326109D01*
X798802Y-326259D01*
X798762Y-326459D01*
X798802Y-326659D01*
X798882Y-326809D01*
X799002Y-326909D01*
X799142Y-326959D01*
X799282Y-326934D01*
X799402Y-326859D01*
X799482Y-326759D01*
G01X800022Y-326784D02*
X800122Y-326884D01*
X800262Y-326959D01*
X800382D01*
X800502Y-326909D01*
X800582Y-326834D01*
X800622Y-326734D01*
X800602Y-326584D01*
X800522Y-326509D01*
X800162Y-326359D01*
X800082Y-326184D01*
X800122Y-326059D01*
X800202Y-325984D01*
X800322Y-325959D01*
X800442Y-325984D01*
X800562Y-326059D01*
G01X801222Y-326284D02*
X801862D01*
X801802Y-326109D01*
X801702Y-326009D01*
X801562Y-325959D01*
X801422Y-325984D01*
X801302Y-326059D01*
X801222Y-326234D01*
X801182Y-326384D01*
Y-326534D01*
X801222Y-326684D01*
X801322Y-326834D01*
X801442Y-326934D01*
X801582Y-326959D01*
X801722Y-326909D01*
X801862Y-326759D01*
G01X802362Y-326959D02*
Y-325459D01*
G01Y-326209D02*
X802462Y-326059D01*
X802582Y-325984D01*
X802702Y-325959D01*
X802882Y-326009D01*
X803002Y-326109D01*
X803082Y-326284D01*
Y-326484D01*
X803042Y-326684D01*
X802962Y-326834D01*
X802822Y-326934D01*
X802702Y-326959D01*
X802582Y-326934D01*
X802462Y-326859D01*
X802362Y-326734D01*
G01X803922Y-326959D02*
X803802Y-326934D01*
X803682Y-326834D01*
X803602Y-326659D01*
X803562Y-326459D01*
X803602Y-326259D01*
X803682Y-326084D01*
X803802Y-325984D01*
X803922Y-325959D01*
X804042Y-325984D01*
X804162Y-326084D01*
X804242Y-326259D01*
X804262Y-326459D01*
X804242Y-326659D01*
X804162Y-326834D01*
X804042Y-326934D01*
X803922Y-326959D01*
G01X805482D02*
Y-325959D01*
G01Y-326134D02*
X805402Y-326034D01*
X805282Y-325984D01*
X805142Y-325959D01*
X805002Y-326009D01*
X804882Y-326109D01*
X804802Y-326259D01*
X804762Y-326459D01*
X804802Y-326659D01*
X804882Y-326809D01*
X805002Y-326909D01*
X805142Y-326959D01*
X805282Y-326934D01*
X805402Y-326859D01*
X805482Y-326759D01*
G01X806042Y-326959D02*
Y-325959D01*
G01Y-326159D02*
X806142Y-326059D01*
X806242Y-325984D01*
X806382Y-325959D01*
X806482Y-325984D01*
X806602Y-326059D01*
G01X807882Y-325459D02*
Y-326959D01*
G01Y-326734D02*
X807802Y-326859D01*
X807682Y-326934D01*
X807542Y-326959D01*
X807382Y-326909D01*
X807262Y-326784D01*
X807182Y-326634D01*
X807162Y-326459D01*
X807182Y-326284D01*
X807262Y-326134D01*
X807382Y-326009D01*
X807542Y-325959D01*
X807682Y-325984D01*
X807782Y-326034D01*
X807882Y-326134D01*
G01X809522Y-326959D02*
Y-325459D01*
X810022D01*
X810182Y-325534D01*
X810282Y-325634D01*
X810322Y-325834D01*
X810282Y-326034D01*
X810162Y-326159D01*
X810022Y-326234D01*
X809522D01*
G01X810022D02*
X810322Y-326959D01*
G01X810822Y-326284D02*
X811462D01*
X811402Y-326109D01*
X811302Y-326009D01*
X811162Y-325959D01*
X811022Y-325984D01*
X810902Y-326059D01*
X810822Y-326234D01*
X810782Y-326384D01*
Y-326534D01*
X810822Y-326684D01*
X810922Y-326834D01*
X811042Y-326934D01*
X811182Y-326959D01*
X811322Y-326909D01*
X811462Y-326759D01*
G01X811962Y-325959D02*
X812322Y-326959D01*
X812682Y-325959D01*
G01X813522Y-327009D02*
X813482Y-326984D01*
Y-326934D01*
X813522Y-326909D01*
X813562Y-326934D01*
Y-326984D01*
X813522Y-327009D01*
G01X814682Y-326959D02*
X814722Y-326634D01*
X814782Y-326359D01*
X814862Y-326109D01*
X814962Y-325834D01*
X815122Y-325459D01*
X814322D01*
G01X816082Y-326159D02*
X816162Y-326084D01*
X816222Y-325959D01*
X816262Y-325784D01*
X816222Y-325634D01*
X816142Y-325534D01*
X816002Y-325459D01*
X815462D01*
Y-326959D01*
X816122D01*
X816262Y-326859D01*
X816342Y-326709D01*
X816382Y-326534D01*
X816342Y-326359D01*
X816222Y-326209D01*
X816082Y-326159D01*
X815462D01*
G01X822046Y0D02*
G03X837794Y15748I0J15748D01*
G01D02*
Y1311024D01*
G01X845668Y187035D02*
G03X837794I-3937J0D01*
G01X845668Y206721D02*
G02X837794I-3937J0D01*
G01Y309409D02*
G02X845668I3937J0D01*
G01X837794Y329095D02*
G03X845668I3937J0D01*
G01X837794Y552755D02*
G02X845668I3937J0D01*
G01X837794Y572441D02*
G03X845668I3937J0D01*
G01X837794Y693880D02*
G02X845668I3937J0D01*
G01X837794Y713566D02*
G03X845668I3937J0D01*
G01Y914527D02*
G03X837794I-3937J0D01*
G01X845668Y934213D02*
G02X837794I-3937J0D01*
G01X845668Y1029527D02*
G03X837794I-3937J0D01*
G01X845668Y1049213D02*
G02X837794I-3937J0D01*
G01Y1277559D02*
G02X845668I3937J0D01*
G01X837794D02*
G02X845668I3937J0D01*
G01X837794Y1297244D02*
G03X845668I3937J0D01*
G01X837794D02*
G03X845668I3937J0D01*
G01X837794Y1311024D02*
G03X822046Y1326772I-15748J0D01*
G01X837794Y1329762D02*
Y1366162D01*
G01X845668Y7874D02*
Y79000D01*
G01X853542Y0D02*
G02X845668Y7874I0J7874D01*
G01X877164Y0D02*
X853542D01*
G01X860667D02*
X992500D01*
G01X845668Y1275772D02*
Y79000D01*
G01Y1318898D02*
Y1275772D01*
G01X853542Y1326772D02*
G03X845668Y1318898I0J-7874D01*
G01X877164Y1326772D02*
X853542D01*
G01X885038Y79000D02*
Y7874D01*
G02X877164Y0I-7874J0D01*
G01X885038Y1275772D02*
Y79000D01*
G01Y1234543D02*
Y1440000D01*
G01Y1275772D02*
Y1318898D01*
G03X877164Y1326772I-7874J0D01*
G01X871769D02*
X992500D01*
G01X885038Y1336615D02*
Y1406851D01*
G01X880038Y1438000D02*
X885038Y1439000D01*
X880038Y1440000D01*
Y1438000D01*
G01X894881Y0D02*
X934668D01*
G01X894881Y1326772D02*
X980353D01*
G01X991500Y622775D02*
Y0D01*
G01X990500Y5000D02*
X991500Y0D01*
X992500Y5000D01*
X990500D01*
G01X1010250Y658950D02*
Y654300D01*
X997750D01*
Y658950D01*
G01X1010250Y702350D02*
Y707000D01*
X997750D01*
Y702350D01*
G01X991500Y738225D02*
Y1326772D01*
G01X992500Y1321772D02*
X991500Y1326772D01*
X990500Y1321772D01*
X992500D01*
G01X1242635Y95439D02*
X1242888Y95689D01*
X1243078Y96105D01*
X1243205Y96689D01*
X1243078Y97189D01*
X1242825Y97522D01*
X1242381Y97772D01*
X1240671D01*
Y92772D01*
X1242761D01*
X1243205Y93105D01*
X1243458Y93605D01*
X1243585Y94189D01*
X1243458Y94772D01*
X1243078Y95272D01*
X1242635Y95439D01*
X1240671D01*
G01X1246341Y92772D02*
Y96105D01*
G01Y95439D02*
X1246658Y95772D01*
X1246975Y96022D01*
X1247418Y96105D01*
X1247735Y96022D01*
X1248115Y95772D01*
G01X1251378Y95022D02*
X1253405D01*
X1253215Y95605D01*
X1252898Y95939D01*
X1252455Y96105D01*
X1252011Y96022D01*
X1251631Y95772D01*
X1251378Y95189D01*
X1251251Y94689D01*
Y94189D01*
X1251378Y93689D01*
X1251695Y93189D01*
X1252075Y92855D01*
X1252518Y92772D01*
X1252961Y92939D01*
X1253405Y93439D01*
G01X1258568Y92772D02*
Y96105D01*
G01Y95522D02*
X1258315Y95855D01*
X1257935Y96022D01*
X1257491Y96105D01*
X1257048Y95939D01*
X1256668Y95605D01*
X1256415Y95105D01*
X1256288Y94439D01*
X1256415Y93772D01*
X1256668Y93272D01*
X1257048Y92939D01*
X1257491Y92772D01*
X1257935Y92855D01*
X1258315Y93105D01*
X1258568Y93439D01*
G01X1261451Y92772D02*
Y97772D01*
G01X1263478Y96105D02*
X1261451Y94189D01*
G01X1262275Y94939D02*
X1263605Y92772D01*
G01X1267628Y97772D02*
Y92772D01*
G01X1266741Y96105D02*
X1268515D01*
G01X1273868Y92772D02*
Y96105D01*
G01Y95522D02*
X1273615Y95855D01*
X1273235Y96022D01*
X1272791Y96105D01*
X1272348Y95939D01*
X1271968Y95605D01*
X1271715Y95105D01*
X1271588Y94439D01*
X1271715Y93772D01*
X1271968Y93272D01*
X1272348Y92939D01*
X1272791Y92772D01*
X1273235Y92855D01*
X1273615Y93105D01*
X1273868Y93439D01*
G01X1276688Y92772D02*
Y97772D01*
G01Y95272D02*
X1277005Y95772D01*
X1277385Y96022D01*
X1277765Y96105D01*
X1278335Y95939D01*
X1278715Y95605D01*
X1278968Y95022D01*
Y94355D01*
X1278841Y93689D01*
X1278588Y93189D01*
X1278145Y92855D01*
X1277765Y92772D01*
X1277385Y92855D01*
X1277005Y93105D01*
X1276688Y93522D01*
G01X1282928Y92605D02*
X1282801Y92689D01*
Y92855D01*
X1282928Y92939D01*
X1283055Y92855D01*
Y92689D01*
X1282928Y92605D01*
G01Y94855D02*
X1282801Y94939D01*
Y95105D01*
X1282928Y95189D01*
X1283055Y95105D01*
Y94939D01*
X1282928Y94855D01*
G01X1317425Y159302D02*
Y164302D01*
X1319831D01*
G01X1318945Y161885D02*
X1317425D01*
G01X1323728Y159302D02*
X1323348Y159385D01*
X1322968Y159719D01*
X1322715Y160302D01*
X1322588Y160969D01*
X1322715Y161635D01*
X1322968Y162219D01*
X1323348Y162552D01*
X1323728Y162635D01*
X1324108Y162552D01*
X1324488Y162219D01*
X1324741Y161635D01*
X1324805Y160969D01*
X1324741Y160302D01*
X1324488Y159719D01*
X1324108Y159385D01*
X1323728Y159302D01*
G01X1327941D02*
Y162635D01*
G01Y161969D02*
X1328258Y162302D01*
X1328575Y162552D01*
X1329018Y162635D01*
X1329335Y162552D01*
X1329715Y162302D01*
G01X1337761Y159302D02*
Y164302D01*
X1339281D01*
X1339788Y164052D01*
X1340168Y163469D01*
X1340295Y162802D01*
X1340168Y162135D01*
X1339851Y161635D01*
X1339281Y161385D01*
X1337761D01*
G01X1345268Y159302D02*
Y162635D01*
G01Y162052D02*
X1345015Y162385D01*
X1344635Y162552D01*
X1344191Y162635D01*
X1343748Y162469D01*
X1343368Y162135D01*
X1343115Y161635D01*
X1342988Y160969D01*
X1343115Y160302D01*
X1343368Y159802D01*
X1343748Y159469D01*
X1344191Y159302D01*
X1344635Y159385D01*
X1345015Y159635D01*
X1345268Y159969D01*
G01X1348151Y159302D02*
Y162635D01*
G01Y161802D02*
X1348405Y162219D01*
X1348785Y162552D01*
X1349291Y162635D01*
X1349735Y162552D01*
X1350115Y162219D01*
X1350305Y161635D01*
Y159302D01*
G01X1353378Y161552D02*
X1355405D01*
X1355215Y162135D01*
X1354898Y162469D01*
X1354455Y162635D01*
X1354011Y162552D01*
X1353631Y162302D01*
X1353378Y161719D01*
X1353251Y161219D01*
Y160719D01*
X1353378Y160219D01*
X1353695Y159719D01*
X1354075Y159385D01*
X1354518Y159302D01*
X1354961Y159469D01*
X1355405Y159969D01*
G01X1359428Y159302D02*
Y164302D01*
G01X1370135Y161969D02*
X1370388Y162219D01*
X1370578Y162635D01*
X1370705Y163219D01*
X1370578Y163719D01*
X1370325Y164052D01*
X1369881Y164302D01*
X1368171D01*
Y159302D01*
X1370261D01*
X1370705Y159635D01*
X1370958Y160135D01*
X1371085Y160719D01*
X1370958Y161302D01*
X1370578Y161802D01*
X1370135Y161969D01*
X1368171D01*
G01X1374728Y159302D02*
X1374348Y159385D01*
X1373968Y159719D01*
X1373715Y160302D01*
X1373588Y160969D01*
X1373715Y161635D01*
X1373968Y162219D01*
X1374348Y162552D01*
X1374728Y162635D01*
X1375108Y162552D01*
X1375488Y162219D01*
X1375741Y161635D01*
X1375805Y160969D01*
X1375741Y160302D01*
X1375488Y159719D01*
X1375108Y159385D01*
X1374728Y159302D01*
G01X1380968D02*
Y162635D01*
G01Y162052D02*
X1380715Y162385D01*
X1380335Y162552D01*
X1379891Y162635D01*
X1379448Y162469D01*
X1379068Y162135D01*
X1378815Y161635D01*
X1378688Y160969D01*
X1378815Y160302D01*
X1379068Y159802D01*
X1379448Y159469D01*
X1379891Y159302D01*
X1380335Y159385D01*
X1380715Y159635D01*
X1380968Y159969D01*
G01X1384041Y159302D02*
Y162635D01*
G01Y161969D02*
X1384358Y162302D01*
X1384675Y162552D01*
X1385118Y162635D01*
X1385435Y162552D01*
X1385815Y162302D01*
G01X1391168Y164302D02*
Y159302D01*
G01Y160052D02*
X1390915Y159635D01*
X1390535Y159385D01*
X1390091Y159302D01*
X1389585Y159469D01*
X1389205Y159885D01*
X1388951Y160385D01*
X1388888Y160969D01*
X1388951Y161552D01*
X1389205Y162052D01*
X1389585Y162469D01*
X1390091Y162635D01*
X1390535Y162552D01*
X1390851Y162385D01*
X1391168Y162052D01*
G01X1318628Y176902D02*
Y171902D01*
G01X1317171Y176902D02*
X1320085D01*
G01X1323728Y171902D02*
X1323348Y171985D01*
X1322968Y172319D01*
X1322715Y172902D01*
X1322588Y173569D01*
X1322715Y174235D01*
X1322968Y174819D01*
X1323348Y175152D01*
X1323728Y175235D01*
X1324108Y175152D01*
X1324488Y174819D01*
X1324741Y174235D01*
X1324805Y173569D01*
X1324741Y172902D01*
X1324488Y172319D01*
X1324108Y171985D01*
X1323728Y171902D01*
G01X1327688Y170235D02*
Y175235D01*
G01Y174485D02*
X1328005Y174902D01*
X1328321Y175152D01*
X1328828Y175235D01*
X1329271Y175152D01*
X1329715Y174735D01*
X1329905Y174152D01*
X1329968Y173569D01*
X1329905Y172985D01*
X1329715Y172402D01*
X1329335Y172069D01*
X1328828Y171902D01*
X1328385Y171985D01*
X1327941Y172235D01*
X1327688Y172569D01*
G01X1337445Y171902D02*
X1339028Y176902D01*
X1340611Y171902D01*
G01X1340041Y173652D02*
X1338015D01*
G01X1343051Y171902D02*
Y175235D01*
G01Y174402D02*
X1343305Y174819D01*
X1343685Y175152D01*
X1344191Y175235D01*
X1344635Y175152D01*
X1345015Y174819D01*
X1345205Y174235D01*
Y171902D01*
G01X1350368Y176902D02*
Y171902D01*
G01Y172652D02*
X1350115Y172235D01*
X1349735Y171985D01*
X1349291Y171902D01*
X1348785Y172069D01*
X1348405Y172485D01*
X1348151Y172985D01*
X1348088Y173569D01*
X1348151Y174152D01*
X1348405Y174652D01*
X1348785Y175069D01*
X1349291Y175235D01*
X1349735Y175152D01*
X1350051Y174985D01*
X1350368Y174652D01*
G01X1359935Y174569D02*
X1360188Y174819D01*
X1360378Y175235D01*
X1360505Y175819D01*
X1360378Y176319D01*
X1360125Y176652D01*
X1359681Y176902D01*
X1357971D01*
Y171902D01*
X1360061D01*
X1360505Y172235D01*
X1360758Y172735D01*
X1360885Y173319D01*
X1360758Y173902D01*
X1360378Y174402D01*
X1359935Y174569D01*
X1357971D01*
G01X1364528Y171902D02*
X1364148Y171985D01*
X1363768Y172319D01*
X1363515Y172902D01*
X1363388Y173569D01*
X1363515Y174235D01*
X1363768Y174819D01*
X1364148Y175152D01*
X1364528Y175235D01*
X1364908Y175152D01*
X1365288Y174819D01*
X1365541Y174235D01*
X1365605Y173569D01*
X1365541Y172902D01*
X1365288Y172319D01*
X1364908Y171985D01*
X1364528Y171902D01*
G01X1369628Y176902D02*
Y171902D01*
G01X1368741Y175235D02*
X1370515D01*
G01X1374728Y176902D02*
Y171902D01*
G01X1373841Y175235D02*
X1375615D01*
G01X1379828Y171902D02*
X1379448Y171985D01*
X1379068Y172319D01*
X1378815Y172902D01*
X1378688Y173569D01*
X1378815Y174235D01*
X1379068Y174819D01*
X1379448Y175152D01*
X1379828Y175235D01*
X1380208Y175152D01*
X1380588Y174819D01*
X1380841Y174235D01*
X1380905Y173569D01*
X1380841Y172902D01*
X1380588Y172319D01*
X1380208Y171985D01*
X1379828Y171902D01*
G01X1383028D02*
Y175235D01*
G01Y174319D02*
X1383218Y174735D01*
X1383535Y175069D01*
X1383978Y175235D01*
X1384421Y175069D01*
X1384738Y174735D01*
X1384928Y174319D01*
Y171902D01*
G01Y174319D02*
X1385118Y174735D01*
X1385435Y175069D01*
X1385878Y175235D01*
X1386321Y175069D01*
X1386638Y174735D01*
X1386828Y174235D01*
Y171902D01*
G01X1393798Y172569D02*
X1394305Y172152D01*
X1394875Y171902D01*
X1395381D01*
X1395888Y172152D01*
X1396268Y172569D01*
X1396458Y173152D01*
X1396331Y173735D01*
X1396015Y174235D01*
X1395445Y174569D01*
X1394685Y174735D01*
X1394241Y175069D01*
X1394051Y175652D01*
X1394178Y176235D01*
X1394495Y176652D01*
X1394938Y176902D01*
X1395381D01*
X1395825Y176735D01*
X1396205Y176319D01*
G01X1400228Y175235D02*
Y171902D01*
G01Y176569D02*
X1400101Y176652D01*
Y176819D01*
X1400228Y176902D01*
X1400355Y176819D01*
Y176652D01*
X1400228Y176569D01*
G01X1406468Y176902D02*
Y171902D01*
G01Y172652D02*
X1406215Y172235D01*
X1405835Y171985D01*
X1405391Y171902D01*
X1404885Y172069D01*
X1404505Y172485D01*
X1404251Y172985D01*
X1404188Y173569D01*
X1404251Y174152D01*
X1404505Y174652D01*
X1404885Y175069D01*
X1405391Y175235D01*
X1405835Y175152D01*
X1406151Y174985D01*
X1406468Y174652D01*
G01X1409478Y174152D02*
X1411505D01*
X1411315Y174735D01*
X1410998Y175069D01*
X1410555Y175235D01*
X1410111Y175152D01*
X1409731Y174902D01*
X1409478Y174319D01*
X1409351Y173819D01*
Y173319D01*
X1409478Y172819D01*
X1409795Y172319D01*
X1410175Y171985D01*
X1410618Y171902D01*
X1411061Y172069D01*
X1411505Y172569D01*
G01X1317425Y159302D02*
Y164302D01*
X1319831D01*
G01X1318945Y161885D02*
X1317425D01*
G01X1323728Y159302D02*
X1323348Y159385D01*
X1322968Y159719D01*
X1322715Y160302D01*
X1322588Y160969D01*
X1322715Y161635D01*
X1322968Y162219D01*
X1323348Y162552D01*
X1323728Y162635D01*
X1324108Y162552D01*
X1324488Y162219D01*
X1324741Y161635D01*
X1324805Y160969D01*
X1324741Y160302D01*
X1324488Y159719D01*
X1324108Y159385D01*
X1323728Y159302D01*
G01X1327941D02*
Y162635D01*
G01Y161969D02*
X1328258Y162302D01*
X1328575Y162552D01*
X1329018Y162635D01*
X1329335Y162552D01*
X1329715Y162302D01*
G01X1337761Y159302D02*
Y164302D01*
X1339281D01*
X1339788Y164052D01*
X1340168Y163469D01*
X1340295Y162802D01*
X1340168Y162135D01*
X1339851Y161635D01*
X1339281Y161385D01*
X1337761D01*
G01X1345268Y159302D02*
Y162635D01*
G01Y162052D02*
X1345015Y162385D01*
X1344635Y162552D01*
X1344191Y162635D01*
X1343748Y162469D01*
X1343368Y162135D01*
X1343115Y161635D01*
X1342988Y160969D01*
X1343115Y160302D01*
X1343368Y159802D01*
X1343748Y159469D01*
X1344191Y159302D01*
X1344635Y159385D01*
X1345015Y159635D01*
X1345268Y159969D01*
G01X1348151Y159302D02*
Y162635D01*
G01Y161802D02*
X1348405Y162219D01*
X1348785Y162552D01*
X1349291Y162635D01*
X1349735Y162552D01*
X1350115Y162219D01*
X1350305Y161635D01*
Y159302D01*
G01X1353378Y161552D02*
X1355405D01*
X1355215Y162135D01*
X1354898Y162469D01*
X1354455Y162635D01*
X1354011Y162552D01*
X1353631Y162302D01*
X1353378Y161719D01*
X1353251Y161219D01*
Y160719D01*
X1353378Y160219D01*
X1353695Y159719D01*
X1354075Y159385D01*
X1354518Y159302D01*
X1354961Y159469D01*
X1355405Y159969D01*
G01X1359428Y159302D02*
Y164302D01*
G01X1370135Y161969D02*
X1370388Y162219D01*
X1370578Y162635D01*
X1370705Y163219D01*
X1370578Y163719D01*
X1370325Y164052D01*
X1369881Y164302D01*
X1368171D01*
Y159302D01*
X1370261D01*
X1370705Y159635D01*
X1370958Y160135D01*
X1371085Y160719D01*
X1370958Y161302D01*
X1370578Y161802D01*
X1370135Y161969D01*
X1368171D01*
G01X1374728Y159302D02*
X1374348Y159385D01*
X1373968Y159719D01*
X1373715Y160302D01*
X1373588Y160969D01*
X1373715Y161635D01*
X1373968Y162219D01*
X1374348Y162552D01*
X1374728Y162635D01*
X1375108Y162552D01*
X1375488Y162219D01*
X1375741Y161635D01*
X1375805Y160969D01*
X1375741Y160302D01*
X1375488Y159719D01*
X1375108Y159385D01*
X1374728Y159302D01*
G01X1380968D02*
Y162635D01*
G01Y162052D02*
X1380715Y162385D01*
X1380335Y162552D01*
X1379891Y162635D01*
X1379448Y162469D01*
X1379068Y162135D01*
X1378815Y161635D01*
X1378688Y160969D01*
X1378815Y160302D01*
X1379068Y159802D01*
X1379448Y159469D01*
X1379891Y159302D01*
X1380335Y159385D01*
X1380715Y159635D01*
X1380968Y159969D01*
G01X1384041Y159302D02*
Y162635D01*
G01Y161969D02*
X1384358Y162302D01*
X1384675Y162552D01*
X1385118Y162635D01*
X1385435Y162552D01*
X1385815Y162302D01*
G01X1391168Y164302D02*
Y159302D01*
G01Y160052D02*
X1390915Y159635D01*
X1390535Y159385D01*
X1390091Y159302D01*
X1389585Y159469D01*
X1389205Y159885D01*
X1388951Y160385D01*
X1388888Y160969D01*
X1388951Y161552D01*
X1389205Y162052D01*
X1389585Y162469D01*
X1390091Y162635D01*
X1390535Y162552D01*
X1390851Y162385D01*
X1391168Y162052D01*
G01X1240925Y197102D02*
Y202102D01*
X1243331D01*
G01X1242445Y199685D02*
X1240925D01*
G01X1247228Y200435D02*
Y197102D01*
G01Y201769D02*
X1247101Y201852D01*
Y202019D01*
X1247228Y202102D01*
X1247355Y202019D01*
Y201852D01*
X1247228Y201769D01*
G01X1253468Y202102D02*
Y197102D01*
G01Y197852D02*
X1253215Y197435D01*
X1252835Y197185D01*
X1252391Y197102D01*
X1251885Y197269D01*
X1251505Y197685D01*
X1251251Y198185D01*
X1251188Y198769D01*
X1251251Y199352D01*
X1251505Y199852D01*
X1251885Y200269D01*
X1252391Y200435D01*
X1252835Y200352D01*
X1253151Y200185D01*
X1253468Y199852D01*
G01X1256351Y200435D02*
Y198102D01*
X1256605Y197519D01*
X1256985Y197185D01*
X1257428Y197102D01*
X1257871Y197185D01*
X1258251Y197519D01*
X1258505Y198102D01*
G01Y197102D02*
Y200435D01*
G01X1263541Y200019D02*
X1263098Y200352D01*
X1262718Y200435D01*
X1262211Y200269D01*
X1261831Y199935D01*
X1261578Y199352D01*
X1261515Y198769D01*
X1261578Y198185D01*
X1261831Y197685D01*
X1262211Y197269D01*
X1262718Y197102D01*
X1263161Y197269D01*
X1263541Y197602D01*
G01X1267628Y200435D02*
Y197102D01*
G01Y201769D02*
X1267501Y201852D01*
Y202019D01*
X1267628Y202102D01*
X1267755Y202019D01*
Y201852D01*
X1267628Y201769D01*
G01X1273868Y197102D02*
Y200435D01*
G01Y199852D02*
X1273615Y200185D01*
X1273235Y200352D01*
X1272791Y200435D01*
X1272348Y200269D01*
X1271968Y199935D01*
X1271715Y199435D01*
X1271588Y198769D01*
X1271715Y198102D01*
X1271968Y197602D01*
X1272348Y197269D01*
X1272791Y197102D01*
X1273235Y197185D01*
X1273615Y197435D01*
X1273868Y197769D01*
G01X1277828Y197102D02*
Y202102D01*
G01X1286381Y197102D02*
Y202102D01*
X1288028Y197935D01*
X1289675Y202102D01*
Y197102D01*
G01X1294268D02*
Y200435D01*
G01Y199852D02*
X1294015Y200185D01*
X1293635Y200352D01*
X1293191Y200435D01*
X1292748Y200269D01*
X1292368Y199935D01*
X1292115Y199435D01*
X1291988Y198769D01*
X1292115Y198102D01*
X1292368Y197602D01*
X1292748Y197269D01*
X1293191Y197102D01*
X1293635Y197185D01*
X1294015Y197435D01*
X1294268Y197769D01*
G01X1297341Y197102D02*
Y200435D01*
G01Y199769D02*
X1297658Y200102D01*
X1297975Y200352D01*
X1298418Y200435D01*
X1298735Y200352D01*
X1299115Y200102D01*
G01X1302251Y197102D02*
Y202102D01*
G01X1304278Y200435D02*
X1302251Y198519D01*
G01X1303075Y199269D02*
X1304405Y197102D01*
G01X1308428Y196935D02*
X1308301Y197019D01*
Y197185D01*
X1308428Y197269D01*
X1308555Y197185D01*
Y197019D01*
X1308428Y196935D01*
G01Y199185D02*
X1308301Y199269D01*
Y199435D01*
X1308428Y199519D01*
X1308555Y199435D01*
Y199269D01*
X1308428Y199185D01*
G01X1317235Y197102D02*
Y202102D01*
X1318501D01*
X1319008Y201852D01*
X1319388Y201519D01*
X1319705Y201019D01*
X1319958Y200435D01*
X1320021Y199602D01*
X1319958Y198769D01*
X1319705Y198185D01*
X1319388Y197685D01*
X1319008Y197352D01*
X1318501Y197102D01*
X1317235D01*
G01X1323728Y200435D02*
Y197102D01*
G01Y201769D02*
X1323601Y201852D01*
Y202019D01*
X1323728Y202102D01*
X1323855Y202019D01*
Y201852D01*
X1323728Y201769D01*
G01X1329968Y197102D02*
Y200435D01*
G01Y199852D02*
X1329715Y200185D01*
X1329335Y200352D01*
X1328891Y200435D01*
X1328448Y200269D01*
X1328068Y199935D01*
X1327815Y199435D01*
X1327688Y198769D01*
X1327815Y198102D01*
X1328068Y197602D01*
X1328448Y197269D01*
X1328891Y197102D01*
X1329335Y197185D01*
X1329715Y197435D01*
X1329968Y197769D01*
G01X1332028Y197102D02*
Y200435D01*
G01Y199519D02*
X1332218Y199935D01*
X1332535Y200269D01*
X1332978Y200435D01*
X1333421Y200269D01*
X1333738Y199935D01*
X1333928Y199519D01*
Y197102D01*
G01Y199519D02*
X1334118Y199935D01*
X1334435Y200269D01*
X1334878Y200435D01*
X1335321Y200269D01*
X1335638Y199935D01*
X1335828Y199435D01*
Y197102D01*
G01X1338078Y199352D02*
X1340105D01*
X1339915Y199935D01*
X1339598Y200269D01*
X1339155Y200435D01*
X1338711Y200352D01*
X1338331Y200102D01*
X1338078Y199519D01*
X1337951Y199019D01*
Y198519D01*
X1338078Y198019D01*
X1338395Y197519D01*
X1338775Y197185D01*
X1339218Y197102D01*
X1339661Y197269D01*
X1340105Y197769D01*
G01X1344128Y202102D02*
Y197102D01*
G01X1343241Y200435D02*
X1345015D01*
G01X1348278Y199352D02*
X1350305D01*
X1350115Y199935D01*
X1349798Y200269D01*
X1349355Y200435D01*
X1348911Y200352D01*
X1348531Y200102D01*
X1348278Y199519D01*
X1348151Y199019D01*
Y198519D01*
X1348278Y198019D01*
X1348595Y197519D01*
X1348975Y197185D01*
X1349418Y197102D01*
X1349861Y197269D01*
X1350305Y197769D01*
G01X1353441Y197102D02*
Y200435D01*
G01Y199769D02*
X1353758Y200102D01*
X1354075Y200352D01*
X1354518Y200435D01*
X1354835Y200352D01*
X1355215Y200102D01*
G01X1364528Y197102D02*
Y202102D01*
X1363768Y201102D01*
G01Y197102D02*
X1365288D01*
G01X1367728D02*
Y200435D01*
G01Y199519D02*
X1367918Y199935D01*
X1368235Y200269D01*
X1368678Y200435D01*
X1369121Y200269D01*
X1369438Y199935D01*
X1369628Y199519D01*
Y197102D01*
G01Y199519D02*
X1369818Y199935D01*
X1370135Y200269D01*
X1370578Y200435D01*
X1371021Y200269D01*
X1371338Y199935D01*
X1371528Y199435D01*
Y197102D01*
G01X1372828D02*
Y200435D01*
G01Y199519D02*
X1373018Y199935D01*
X1373335Y200269D01*
X1373778Y200435D01*
X1374221Y200269D01*
X1374538Y199935D01*
X1374728Y199519D01*
Y197102D01*
G01Y199519D02*
X1374918Y199935D01*
X1375235Y200269D01*
X1375678Y200435D01*
X1376121Y200269D01*
X1376438Y199935D01*
X1376628Y199435D01*
Y197102D01*
G01X1386321Y201685D02*
X1385941Y201935D01*
X1385498Y202102D01*
X1384991D01*
X1384421Y201852D01*
X1383978Y201435D01*
X1383661Y200935D01*
X1383408Y200102D01*
X1383345Y199352D01*
X1383471Y198602D01*
X1383661Y198102D01*
X1384041Y197602D01*
X1384485Y197269D01*
X1384928Y197102D01*
X1385371D01*
X1385815Y197269D01*
X1386195Y197519D01*
X1386511Y197852D01*
G01X1390028Y197102D02*
X1389648Y197185D01*
X1389268Y197519D01*
X1389015Y198102D01*
X1388888Y198769D01*
X1389015Y199435D01*
X1389268Y200019D01*
X1389648Y200352D01*
X1390028Y200435D01*
X1390408Y200352D01*
X1390788Y200019D01*
X1391041Y199435D01*
X1391105Y198769D01*
X1391041Y198102D01*
X1390788Y197519D01*
X1390408Y197185D01*
X1390028Y197102D01*
G01X1393988Y195435D02*
Y200435D01*
G01Y199685D02*
X1394305Y200102D01*
X1394621Y200352D01*
X1395128Y200435D01*
X1395571Y200352D01*
X1396015Y199935D01*
X1396205Y199352D01*
X1396268Y198769D01*
X1396205Y198185D01*
X1396015Y197602D01*
X1395635Y197269D01*
X1395128Y197102D01*
X1394685Y197185D01*
X1394241Y197435D01*
X1393988Y197769D01*
G01X1399088Y195435D02*
Y200435D01*
G01Y199685D02*
X1399405Y200102D01*
X1399721Y200352D01*
X1400228Y200435D01*
X1400671Y200352D01*
X1401115Y199935D01*
X1401305Y199352D01*
X1401368Y198769D01*
X1401305Y198185D01*
X1401115Y197602D01*
X1400735Y197269D01*
X1400228Y197102D01*
X1399785Y197185D01*
X1399341Y197435D01*
X1399088Y197769D01*
G01X1404378Y199352D02*
X1406405D01*
X1406215Y199935D01*
X1405898Y200269D01*
X1405455Y200435D01*
X1405011Y200352D01*
X1404631Y200102D01*
X1404378Y199519D01*
X1404251Y199019D01*
Y198519D01*
X1404378Y198019D01*
X1404695Y197519D01*
X1405075Y197185D01*
X1405518Y197102D01*
X1405961Y197269D01*
X1406405Y197769D01*
G01X1409541Y197102D02*
Y200435D01*
G01Y199769D02*
X1409858Y200102D01*
X1410175Y200352D01*
X1410618Y200435D01*
X1410935Y200352D01*
X1411315Y200102D01*
G01X1317235Y184502D02*
Y189502D01*
X1318501D01*
X1319008Y189252D01*
X1319388Y188919D01*
X1319705Y188419D01*
X1319958Y187835D01*
X1320021Y187002D01*
X1319958Y186169D01*
X1319705Y185585D01*
X1319388Y185085D01*
X1319008Y184752D01*
X1318501Y184502D01*
X1317235D01*
G01X1323728Y187835D02*
Y184502D01*
G01Y189169D02*
X1323601Y189252D01*
Y189419D01*
X1323728Y189502D01*
X1323855Y189419D01*
Y189252D01*
X1323728Y189169D01*
G01X1329968Y184502D02*
Y187835D01*
G01Y187252D02*
X1329715Y187585D01*
X1329335Y187752D01*
X1328891Y187835D01*
X1328448Y187669D01*
X1328068Y187335D01*
X1327815Y186835D01*
X1327688Y186169D01*
X1327815Y185502D01*
X1328068Y185002D01*
X1328448Y184669D01*
X1328891Y184502D01*
X1329335Y184585D01*
X1329715Y184835D01*
X1329968Y185169D01*
G01X1332028Y184502D02*
Y187835D01*
G01Y186919D02*
X1332218Y187335D01*
X1332535Y187669D01*
X1332978Y187835D01*
X1333421Y187669D01*
X1333738Y187335D01*
X1333928Y186919D01*
Y184502D01*
G01Y186919D02*
X1334118Y187335D01*
X1334435Y187669D01*
X1334878Y187835D01*
X1335321Y187669D01*
X1335638Y187335D01*
X1335828Y186835D01*
Y184502D01*
G01X1338078Y186752D02*
X1340105D01*
X1339915Y187335D01*
X1339598Y187669D01*
X1339155Y187835D01*
X1338711Y187752D01*
X1338331Y187502D01*
X1338078Y186919D01*
X1337951Y186419D01*
Y185919D01*
X1338078Y185419D01*
X1338395Y184919D01*
X1338775Y184585D01*
X1339218Y184502D01*
X1339661Y184669D01*
X1340105Y185169D01*
G01X1344128Y189502D02*
Y184502D01*
G01X1343241Y187835D02*
X1345015D01*
G01X1348278Y186752D02*
X1350305D01*
X1350115Y187335D01*
X1349798Y187669D01*
X1349355Y187835D01*
X1348911Y187752D01*
X1348531Y187502D01*
X1348278Y186919D01*
X1348151Y186419D01*
Y185919D01*
X1348278Y185419D01*
X1348595Y184919D01*
X1348975Y184585D01*
X1349418Y184502D01*
X1349861Y184669D01*
X1350305Y185169D01*
G01X1353441Y184502D02*
Y187835D01*
G01Y187169D02*
X1353758Y187502D01*
X1354075Y187752D01*
X1354518Y187835D01*
X1354835Y187752D01*
X1355215Y187502D01*
G01X1363135Y185502D02*
X1363515Y184919D01*
X1364021Y184585D01*
X1364591Y184502D01*
X1365098Y184585D01*
X1365605Y185002D01*
X1365921Y185502D01*
X1365985Y186002D01*
X1365858Y186585D01*
X1365415Y187002D01*
X1364971Y187169D01*
X1364401D01*
G01X1364971D02*
X1365351Y187419D01*
X1365668Y187835D01*
X1365795Y188335D01*
X1365668Y188835D01*
X1365351Y189252D01*
X1364781Y189502D01*
X1364211Y189419D01*
X1363641Y189085D01*
G01X1367728Y184502D02*
Y187835D01*
G01Y186919D02*
X1367918Y187335D01*
X1368235Y187669D01*
X1368678Y187835D01*
X1369121Y187669D01*
X1369438Y187335D01*
X1369628Y186919D01*
Y184502D01*
G01Y186919D02*
X1369818Y187335D01*
X1370135Y187669D01*
X1370578Y187835D01*
X1371021Y187669D01*
X1371338Y187335D01*
X1371528Y186835D01*
Y184502D01*
G01X1372828D02*
Y187835D01*
G01Y186919D02*
X1373018Y187335D01*
X1373335Y187669D01*
X1373778Y187835D01*
X1374221Y187669D01*
X1374538Y187335D01*
X1374728Y186919D01*
Y184502D01*
G01Y186919D02*
X1374918Y187335D01*
X1375235Y187669D01*
X1375678Y187835D01*
X1376121Y187669D01*
X1376438Y187335D01*
X1376628Y186835D01*
Y184502D01*
G01X1383598Y185169D02*
X1384105Y184752D01*
X1384675Y184502D01*
X1385181D01*
X1385688Y184752D01*
X1386068Y185169D01*
X1386258Y185752D01*
X1386131Y186335D01*
X1385815Y186835D01*
X1385245Y187169D01*
X1384485Y187335D01*
X1384041Y187669D01*
X1383851Y188252D01*
X1383978Y188835D01*
X1384295Y189252D01*
X1384738Y189502D01*
X1385181D01*
X1385625Y189335D01*
X1386005Y188919D01*
G01X1390028Y184502D02*
X1389648Y184585D01*
X1389268Y184919D01*
X1389015Y185502D01*
X1388888Y186169D01*
X1389015Y186835D01*
X1389268Y187419D01*
X1389648Y187752D01*
X1390028Y187835D01*
X1390408Y187752D01*
X1390788Y187419D01*
X1391041Y186835D01*
X1391105Y186169D01*
X1391041Y185502D01*
X1390788Y184919D01*
X1390408Y184585D01*
X1390028Y184502D01*
G01X1395128D02*
Y189502D01*
G01X1401368D02*
Y184502D01*
G01Y185252D02*
X1401115Y184835D01*
X1400735Y184585D01*
X1400291Y184502D01*
X1399785Y184669D01*
X1399405Y185085D01*
X1399151Y185585D01*
X1399088Y186169D01*
X1399151Y186752D01*
X1399405Y187252D01*
X1399785Y187669D01*
X1400291Y187835D01*
X1400735Y187752D01*
X1401051Y187585D01*
X1401368Y187252D01*
G01X1404378Y186752D02*
X1406405D01*
X1406215Y187335D01*
X1405898Y187669D01*
X1405455Y187835D01*
X1405011Y187752D01*
X1404631Y187502D01*
X1404378Y186919D01*
X1404251Y186419D01*
Y185919D01*
X1404378Y185419D01*
X1404695Y184919D01*
X1405075Y184585D01*
X1405518Y184502D01*
X1405961Y184669D01*
X1406405Y185169D01*
G01X1409541Y184502D02*
Y187835D01*
G01Y187169D02*
X1409858Y187502D01*
X1410175Y187752D01*
X1410618Y187835D01*
X1410935Y187752D01*
X1411315Y187502D01*
G01X1413628Y184502D02*
Y187835D01*
G01Y186919D02*
X1413818Y187335D01*
X1414135Y187669D01*
X1414578Y187835D01*
X1415021Y187669D01*
X1415338Y187335D01*
X1415528Y186919D01*
Y184502D01*
G01Y186919D02*
X1415718Y187335D01*
X1416035Y187669D01*
X1416478Y187835D01*
X1416921Y187669D01*
X1417238Y187335D01*
X1417428Y186835D01*
Y184502D01*
G01X1421768D02*
Y187835D01*
G01Y187252D02*
X1421515Y187585D01*
X1421135Y187752D01*
X1420691Y187835D01*
X1420248Y187669D01*
X1419868Y187335D01*
X1419615Y186835D01*
X1419488Y186169D01*
X1419615Y185502D01*
X1419868Y185002D01*
X1420248Y184669D01*
X1420691Y184502D01*
X1421135Y184585D01*
X1421515Y184835D01*
X1421768Y185169D01*
G01X1424778Y185085D02*
X1425095Y184752D01*
X1425538Y184502D01*
X1425918D01*
X1426298Y184669D01*
X1426551Y184919D01*
X1426678Y185252D01*
X1426615Y185752D01*
X1426361Y186002D01*
X1425221Y186502D01*
X1424968Y187085D01*
X1425095Y187502D01*
X1425348Y187752D01*
X1425728Y187835D01*
X1426108Y187752D01*
X1426488Y187502D01*
G01X1429751Y184502D02*
Y189502D01*
G01X1431778Y187835D02*
X1429751Y185919D01*
G01X1430575Y186669D02*
X1431905Y184502D01*
G01X1314316Y258794D02*
Y253794D01*
G01X1312859Y258794D02*
X1315773D01*
G01X1319416Y253794D02*
X1319036Y253877D01*
X1318656Y254211D01*
X1318403Y254794D01*
X1318276Y255461D01*
X1318403Y256127D01*
X1318656Y256711D01*
X1319036Y257044D01*
X1319416Y257127D01*
X1319796Y257044D01*
X1320176Y256711D01*
X1320429Y256127D01*
X1320493Y255461D01*
X1320429Y254794D01*
X1320176Y254211D01*
X1319796Y253877D01*
X1319416Y253794D01*
G01X1324516D02*
Y258794D01*
G01X1328666Y256044D02*
X1330693D01*
X1330503Y256627D01*
X1330186Y256961D01*
X1329743Y257127D01*
X1329299Y257044D01*
X1328919Y256794D01*
X1328666Y256211D01*
X1328539Y255711D01*
Y255211D01*
X1328666Y254711D01*
X1328983Y254211D01*
X1329363Y253877D01*
X1329806Y253794D01*
X1330249Y253961D01*
X1330693Y254461D01*
G01X1333829Y253794D02*
Y257127D01*
G01Y256461D02*
X1334146Y256794D01*
X1334463Y257044D01*
X1334906Y257127D01*
X1335223Y257044D01*
X1335603Y256794D01*
G01X1340956Y253794D02*
Y257127D01*
G01Y256544D02*
X1340703Y256877D01*
X1340323Y257044D01*
X1339879Y257127D01*
X1339436Y256961D01*
X1339056Y256627D01*
X1338803Y256127D01*
X1338676Y255461D01*
X1338803Y254794D01*
X1339056Y254294D01*
X1339436Y253961D01*
X1339879Y253794D01*
X1340323Y253877D01*
X1340703Y254127D01*
X1340956Y254461D01*
G01X1343839Y253794D02*
Y257127D01*
G01Y256294D02*
X1344093Y256711D01*
X1344473Y257044D01*
X1344979Y257127D01*
X1345423Y257044D01*
X1345803Y256711D01*
X1345993Y256127D01*
Y253794D01*
G01X1351029Y256711D02*
X1350586Y257044D01*
X1350206Y257127D01*
X1349699Y256961D01*
X1349319Y256627D01*
X1349066Y256044D01*
X1349003Y255461D01*
X1349066Y254877D01*
X1349319Y254377D01*
X1349699Y253961D01*
X1350206Y253794D01*
X1350649Y253961D01*
X1351029Y254294D01*
G01X1354166Y256044D02*
X1356193D01*
X1356003Y256627D01*
X1355686Y256961D01*
X1355243Y257127D01*
X1354799Y257044D01*
X1354419Y256794D01*
X1354166Y256211D01*
X1354039Y255711D01*
Y255211D01*
X1354166Y254711D01*
X1354483Y254211D01*
X1354863Y253877D01*
X1355306Y253794D01*
X1355749Y253961D01*
X1356193Y254461D01*
G01X1364619Y255461D02*
X1366139D01*
G01X1365316Y256544D02*
Y254377D01*
G01X1370416Y258794D02*
X1369909Y258627D01*
X1369529Y258211D01*
X1369276Y257711D01*
X1369086Y257044D01*
X1369023Y256294D01*
X1369086Y255544D01*
X1369276Y254877D01*
X1369529Y254377D01*
X1369909Y253961D01*
X1370416Y253794D01*
X1370923Y253961D01*
X1371303Y254377D01*
X1371556Y254877D01*
X1371746Y255544D01*
X1371809Y256294D01*
X1371746Y257044D01*
X1371556Y257711D01*
X1371303Y258211D01*
X1370923Y258627D01*
X1370416Y258794D01*
G01X1375516Y253627D02*
X1375389Y253711D01*
Y253877D01*
X1375516Y253961D01*
X1375643Y253877D01*
Y253711D01*
X1375516Y253627D01*
G01X1380616Y258794D02*
X1380109Y258627D01*
X1379729Y258211D01*
X1379476Y257711D01*
X1379286Y257044D01*
X1379223Y256294D01*
X1379286Y255544D01*
X1379476Y254877D01*
X1379729Y254377D01*
X1380109Y253961D01*
X1380616Y253794D01*
X1381123Y253961D01*
X1381503Y254377D01*
X1381756Y254877D01*
X1381946Y255544D01*
X1382009Y256294D01*
X1381946Y257044D01*
X1381756Y257711D01*
X1381503Y258211D01*
X1381123Y258627D01*
X1380616Y258794D01*
G01X1384323Y254544D02*
X1384703Y254127D01*
X1385146Y253877D01*
X1385716Y253794D01*
X1386286Y253961D01*
X1386729Y254294D01*
X1387046Y254877D01*
X1387109Y255544D01*
X1386983Y256211D01*
X1386666Y256627D01*
X1386223Y256961D01*
X1385779Y257044D01*
X1385336Y256961D01*
X1384766Y256627D01*
X1384956Y258794D01*
X1386666D01*
G01X1390816D02*
X1390309Y258627D01*
X1389929Y258211D01*
X1389676Y257711D01*
X1389486Y257044D01*
X1389423Y256294D01*
X1389486Y255544D01*
X1389676Y254877D01*
X1389929Y254377D01*
X1390309Y253961D01*
X1390816Y253794D01*
X1391323Y253961D01*
X1391703Y254377D01*
X1391956Y254877D01*
X1392146Y255544D01*
X1392209Y256294D01*
X1392146Y257044D01*
X1391956Y257711D01*
X1391703Y258211D01*
X1391323Y258627D01*
X1390816Y258794D01*
G01X1395916Y253794D02*
X1396359Y253877D01*
X1396866Y254127D01*
X1397183Y254544D01*
X1397309Y255127D01*
X1397183Y255711D01*
X1396803Y256211D01*
X1396233Y256461D01*
X1395599D01*
X1395219Y256627D01*
X1394903Y257044D01*
X1394776Y257627D01*
X1394966Y258211D01*
X1395409Y258627D01*
X1395916Y258794D01*
X1396423Y258627D01*
X1396866Y258211D01*
X1397056Y257627D01*
X1396929Y257044D01*
X1396613Y256627D01*
X1396233Y256461D01*
X1395599D01*
X1395029Y256211D01*
X1394649Y255711D01*
X1394523Y255127D01*
X1394649Y254544D01*
X1394966Y254127D01*
X1395473Y253877D01*
X1395916Y253794D01*
G01X1399116D02*
Y257127D01*
G01Y256211D02*
X1399306Y256627D01*
X1399623Y256961D01*
X1400066Y257127D01*
X1400509Y256961D01*
X1400826Y256627D01*
X1401016Y256211D01*
Y253794D01*
G01Y256211D02*
X1401206Y256627D01*
X1401523Y256961D01*
X1401966Y257127D01*
X1402409Y256961D01*
X1402726Y256627D01*
X1402916Y256127D01*
Y253794D01*
G01X1404216D02*
Y257127D01*
G01Y256211D02*
X1404406Y256627D01*
X1404723Y256961D01*
X1405166Y257127D01*
X1405609Y256961D01*
X1405926Y256627D01*
X1406116Y256211D01*
Y253794D01*
G01Y256211D02*
X1406306Y256627D01*
X1406623Y256961D01*
X1407066Y257127D01*
X1407509Y256961D01*
X1407826Y256627D01*
X1408016Y256127D01*
Y253794D01*
G01X1410076Y253627D02*
X1412356Y258794D01*
G01X1415493Y255461D02*
X1417139D01*
G01X1421416Y258794D02*
X1420909Y258627D01*
X1420529Y258211D01*
X1420276Y257711D01*
X1420086Y257044D01*
X1420023Y256294D01*
X1420086Y255544D01*
X1420276Y254877D01*
X1420529Y254377D01*
X1420909Y253961D01*
X1421416Y253794D01*
X1421923Y253961D01*
X1422303Y254377D01*
X1422556Y254877D01*
X1422746Y255544D01*
X1422809Y256294D01*
X1422746Y257044D01*
X1422556Y257711D01*
X1422303Y258211D01*
X1421923Y258627D01*
X1421416Y258794D01*
G01X1426516Y253627D02*
X1426389Y253711D01*
Y253877D01*
X1426516Y253961D01*
X1426643Y253877D01*
Y253711D01*
X1426516Y253627D01*
G01X1431616Y258794D02*
X1431109Y258627D01*
X1430729Y258211D01*
X1430476Y257711D01*
X1430286Y257044D01*
X1430223Y256294D01*
X1430286Y255544D01*
X1430476Y254877D01*
X1430729Y254377D01*
X1431109Y253961D01*
X1431616Y253794D01*
X1432123Y253961D01*
X1432503Y254377D01*
X1432756Y254877D01*
X1432946Y255544D01*
X1433009Y256294D01*
X1432946Y257044D01*
X1432756Y257711D01*
X1432503Y258211D01*
X1432123Y258627D01*
X1431616Y258794D01*
G01X1436716D02*
X1436209Y258627D01*
X1435829Y258211D01*
X1435576Y257711D01*
X1435386Y257044D01*
X1435323Y256294D01*
X1435386Y255544D01*
X1435576Y254877D01*
X1435829Y254377D01*
X1436209Y253961D01*
X1436716Y253794D01*
X1437223Y253961D01*
X1437603Y254377D01*
X1437856Y254877D01*
X1438046Y255544D01*
X1438109Y256294D01*
X1438046Y257044D01*
X1437856Y257711D01*
X1437603Y258211D01*
X1437223Y258627D01*
X1436716Y258794D01*
G01X1441816D02*
X1441309Y258627D01*
X1440929Y258211D01*
X1440676Y257711D01*
X1440486Y257044D01*
X1440423Y256294D01*
X1440486Y255544D01*
X1440676Y254877D01*
X1440929Y254377D01*
X1441309Y253961D01*
X1441816Y253794D01*
X1442323Y253961D01*
X1442703Y254377D01*
X1442956Y254877D01*
X1443146Y255544D01*
X1443209Y256294D01*
X1443146Y257044D01*
X1442956Y257711D01*
X1442703Y258211D01*
X1442323Y258627D01*
X1441816Y258794D01*
G01X1446916D02*
X1446409Y258627D01*
X1446029Y258211D01*
X1445776Y257711D01*
X1445586Y257044D01*
X1445523Y256294D01*
X1445586Y255544D01*
X1445776Y254877D01*
X1446029Y254377D01*
X1446409Y253961D01*
X1446916Y253794D01*
X1447423Y253961D01*
X1447803Y254377D01*
X1448056Y254877D01*
X1448246Y255544D01*
X1448309Y256294D01*
X1448246Y257044D01*
X1448056Y257711D01*
X1447803Y258211D01*
X1447423Y258627D01*
X1446916Y258794D01*
G01X1450116Y253794D02*
Y257127D01*
G01Y256211D02*
X1450306Y256627D01*
X1450623Y256961D01*
X1451066Y257127D01*
X1451509Y256961D01*
X1451826Y256627D01*
X1452016Y256211D01*
Y253794D01*
G01Y256211D02*
X1452206Y256627D01*
X1452523Y256961D01*
X1452966Y257127D01*
X1453409Y256961D01*
X1453726Y256627D01*
X1453916Y256127D01*
Y253794D01*
G01X1455216D02*
Y257127D01*
G01Y256211D02*
X1455406Y256627D01*
X1455723Y256961D01*
X1456166Y257127D01*
X1456609Y256961D01*
X1456926Y256627D01*
X1457116Y256211D01*
Y253794D01*
G01Y256211D02*
X1457306Y256627D01*
X1457623Y256961D01*
X1458066Y257127D01*
X1458509Y256961D01*
X1458826Y256627D01*
X1459016Y256127D01*
Y253794D01*
G01X1242916Y271394D02*
Y266394D01*
G01X1241459Y271394D02*
X1244373D01*
G01X1248016Y266394D02*
X1247636Y266477D01*
X1247256Y266811D01*
X1247003Y267394D01*
X1246876Y268061D01*
X1247003Y268727D01*
X1247256Y269311D01*
X1247636Y269644D01*
X1248016Y269727D01*
X1248396Y269644D01*
X1248776Y269311D01*
X1249029Y268727D01*
X1249093Y268061D01*
X1249029Y267394D01*
X1248776Y266811D01*
X1248396Y266477D01*
X1248016Y266394D01*
G01X1253116D02*
X1252736Y266477D01*
X1252356Y266811D01*
X1252103Y267394D01*
X1251976Y268061D01*
X1252103Y268727D01*
X1252356Y269311D01*
X1252736Y269644D01*
X1253116Y269727D01*
X1253496Y269644D01*
X1253876Y269311D01*
X1254129Y268727D01*
X1254193Y268061D01*
X1254129Y267394D01*
X1253876Y266811D01*
X1253496Y266477D01*
X1253116Y266394D01*
G01X1258216D02*
Y271394D01*
G01X1263316Y269727D02*
Y266394D01*
G01Y271061D02*
X1263189Y271144D01*
Y271311D01*
X1263316Y271394D01*
X1263443Y271311D01*
Y271144D01*
X1263316Y271061D01*
G01X1267339Y266394D02*
Y269727D01*
G01Y268894D02*
X1267593Y269311D01*
X1267973Y269644D01*
X1268479Y269727D01*
X1268923Y269644D01*
X1269303Y269311D01*
X1269493Y268727D01*
Y266394D01*
G01X1272629Y265144D02*
X1273073Y264811D01*
X1273579Y264727D01*
X1274023Y264811D01*
X1274403Y265227D01*
X1274656Y265811D01*
Y269727D01*
G01Y269061D02*
X1274403Y269394D01*
X1274023Y269644D01*
X1273579Y269727D01*
X1273073Y269561D01*
X1272756Y269227D01*
X1272503Y268644D01*
X1272376Y268061D01*
X1272439Y267561D01*
X1272693Y266977D01*
X1273073Y266561D01*
X1273579Y266394D01*
X1273959Y266477D01*
X1274403Y266811D01*
X1274656Y267144D01*
G01X1282386Y266394D02*
Y271394D01*
G01X1285046D02*
Y266394D01*
G01Y268894D02*
X1282386D01*
G01X1288816Y266394D02*
X1288436Y266477D01*
X1288056Y266811D01*
X1287803Y267394D01*
X1287676Y268061D01*
X1287803Y268727D01*
X1288056Y269311D01*
X1288436Y269644D01*
X1288816Y269727D01*
X1289196Y269644D01*
X1289576Y269311D01*
X1289829Y268727D01*
X1289893Y268061D01*
X1289829Y267394D01*
X1289576Y266811D01*
X1289196Y266477D01*
X1288816Y266394D01*
G01X1293916D02*
Y271394D01*
G01X1298066Y268644D02*
X1300093D01*
X1299903Y269227D01*
X1299586Y269561D01*
X1299143Y269727D01*
X1298699Y269644D01*
X1298319Y269394D01*
X1298066Y268811D01*
X1297939Y268311D01*
Y267811D01*
X1298066Y267311D01*
X1298383Y266811D01*
X1298763Y266477D01*
X1299206Y266394D01*
X1299649Y266561D01*
X1300093Y267061D01*
G01X1304116Y266227D02*
X1303989Y266311D01*
Y266477D01*
X1304116Y266561D01*
X1304243Y266477D01*
Y266311D01*
X1304116Y266227D01*
G01Y268477D02*
X1303989Y268561D01*
Y268727D01*
X1304116Y268811D01*
X1304243Y268727D01*
Y268561D01*
X1304116Y268477D01*
G01X1312923Y266394D02*
Y271394D01*
X1314189D01*
X1314696Y271144D01*
X1315076Y270811D01*
X1315393Y270311D01*
X1315646Y269727D01*
X1315709Y268894D01*
X1315646Y268061D01*
X1315393Y267477D01*
X1315076Y266977D01*
X1314696Y266644D01*
X1314189Y266394D01*
X1312923D01*
G01X1319416Y269727D02*
Y266394D01*
G01Y271061D02*
X1319289Y271144D01*
Y271311D01*
X1319416Y271394D01*
X1319543Y271311D01*
Y271144D01*
X1319416Y271061D01*
G01X1325656Y266394D02*
Y269727D01*
G01Y269144D02*
X1325403Y269477D01*
X1325023Y269644D01*
X1324579Y269727D01*
X1324136Y269561D01*
X1323756Y269227D01*
X1323503Y268727D01*
X1323376Y268061D01*
X1323503Y267394D01*
X1323756Y266894D01*
X1324136Y266561D01*
X1324579Y266394D01*
X1325023Y266477D01*
X1325403Y266727D01*
X1325656Y267061D01*
G01X1327716Y266394D02*
Y269727D01*
G01Y268811D02*
X1327906Y269227D01*
X1328223Y269561D01*
X1328666Y269727D01*
X1329109Y269561D01*
X1329426Y269227D01*
X1329616Y268811D01*
Y266394D01*
G01Y268811D02*
X1329806Y269227D01*
X1330123Y269561D01*
X1330566Y269727D01*
X1331009Y269561D01*
X1331326Y269227D01*
X1331516Y268727D01*
Y266394D01*
G01X1333766Y268644D02*
X1335793D01*
X1335603Y269227D01*
X1335286Y269561D01*
X1334843Y269727D01*
X1334399Y269644D01*
X1334019Y269394D01*
X1333766Y268811D01*
X1333639Y268311D01*
Y267811D01*
X1333766Y267311D01*
X1334083Y266811D01*
X1334463Y266477D01*
X1334906Y266394D01*
X1335349Y266561D01*
X1335793Y267061D01*
G01X1339816Y271394D02*
Y266394D01*
G01X1338929Y269727D02*
X1340703D01*
G01X1343966Y268644D02*
X1345993D01*
X1345803Y269227D01*
X1345486Y269561D01*
X1345043Y269727D01*
X1344599Y269644D01*
X1344219Y269394D01*
X1343966Y268811D01*
X1343839Y268311D01*
Y267811D01*
X1343966Y267311D01*
X1344283Y266811D01*
X1344663Y266477D01*
X1345106Y266394D01*
X1345549Y266561D01*
X1345993Y267061D01*
G01X1349129Y266394D02*
Y269727D01*
G01Y269061D02*
X1349446Y269394D01*
X1349763Y269644D01*
X1350206Y269727D01*
X1350523Y269644D01*
X1350903Y269394D01*
G01X1358823Y267394D02*
X1359203Y266811D01*
X1359709Y266477D01*
X1360279Y266394D01*
X1360786Y266477D01*
X1361293Y266894D01*
X1361609Y267394D01*
X1361673Y267894D01*
X1361546Y268477D01*
X1361103Y268894D01*
X1360659Y269061D01*
X1360089D01*
G01X1360659D02*
X1361039Y269311D01*
X1361356Y269727D01*
X1361483Y270227D01*
X1361356Y270727D01*
X1361039Y271144D01*
X1360469Y271394D01*
X1359899Y271311D01*
X1359329Y270977D01*
G01X1365316Y266227D02*
X1365189Y266311D01*
Y266477D01*
X1365316Y266561D01*
X1365443Y266477D01*
Y266311D01*
X1365316Y266227D01*
G01X1370416Y266394D02*
Y271394D01*
X1369656Y270394D01*
G01Y266394D02*
X1371176D01*
G01X1375389D02*
X1375516Y267477D01*
X1375706Y268394D01*
X1375959Y269227D01*
X1376276Y270144D01*
X1376783Y271394D01*
X1374249D01*
G01X1379223Y267144D02*
X1379603Y266727D01*
X1380046Y266477D01*
X1380616Y266394D01*
X1381186Y266561D01*
X1381629Y266894D01*
X1381946Y267477D01*
X1382009Y268144D01*
X1381883Y268811D01*
X1381566Y269227D01*
X1381123Y269561D01*
X1380679Y269644D01*
X1380236Y269561D01*
X1379666Y269227D01*
X1379856Y271394D01*
X1381566D01*
G01X1383816Y266394D02*
Y269727D01*
G01Y268811D02*
X1384006Y269227D01*
X1384323Y269561D01*
X1384766Y269727D01*
X1385209Y269561D01*
X1385526Y269227D01*
X1385716Y268811D01*
Y266394D01*
G01Y268811D02*
X1385906Y269227D01*
X1386223Y269561D01*
X1386666Y269727D01*
X1387109Y269561D01*
X1387426Y269227D01*
X1387616Y268727D01*
Y266394D01*
G01X1388916D02*
Y269727D01*
G01Y268811D02*
X1389106Y269227D01*
X1389423Y269561D01*
X1389866Y269727D01*
X1390309Y269561D01*
X1390626Y269227D01*
X1390816Y268811D01*
Y266394D01*
G01Y268811D02*
X1391006Y269227D01*
X1391323Y269561D01*
X1391766Y269727D01*
X1392209Y269561D01*
X1392526Y269227D01*
X1392716Y268727D01*
Y266394D01*
G01X1399559D02*
Y271394D01*
X1402473Y266394D01*
Y271394D01*
G01X1404849Y266394D02*
Y271394D01*
X1406369D01*
X1406876Y271144D01*
X1407256Y270561D01*
X1407383Y269894D01*
X1407256Y269227D01*
X1406939Y268727D01*
X1406369Y268477D01*
X1404849D01*
G01X1411216Y271394D02*
Y266394D01*
G01X1409759Y271394D02*
X1412673D01*
G01X1414986Y266394D02*
Y271394D01*
G01X1417646D02*
Y266394D01*
G01Y268894D02*
X1414986D01*
G01X1261672Y55742D02*
X1261172Y56122D01*
X1260922Y56565D01*
X1260839Y57072D01*
X1261006Y57705D01*
X1261422Y58148D01*
X1261922Y58275D01*
X1262422Y58212D01*
X1262839Y57958D01*
X1263672Y56692D01*
X1264256Y56122D01*
X1265089Y55742D01*
X1265839Y55615D01*
Y58275D01*
G01X1282906Y60882D02*
X1267945D01*
G01X1282906Y53008D02*
X1267945D01*
G01X1268339Y56945D02*
Y53008D01*
G01X1269323Y47102D02*
X1268339Y53008D01*
X1267354Y47102D01*
X1269323D01*
G01X1268339Y56945D02*
Y60882D01*
G01X1267354Y66787D02*
X1268339Y60882D01*
X1269323Y66787D01*
X1267354D01*
G01X1286362Y124223D02*
X1277352Y124488D01*
G01X1274134Y129136D02*
X1270169Y133622D01*
X1272465Y128093D01*
X1274134Y129136D01*
G01X1270169Y133622D02*
X1283632Y112081D01*
G01X1281251Y138464D02*
X1275718Y136177D01*
X1281694Y136546D01*
X1281251Y138464D01*
G01X1275718Y136177D02*
X1306047Y143176D01*
G01X1281018Y236202D02*
X1275464Y233964D01*
X1281443Y234280D01*
X1281018Y236202D01*
G01X1275464Y233964D02*
X1319567Y243729D01*
G01X1302379Y38791D02*
X1302759Y38208D01*
X1303265Y37874D01*
X1303835Y37791D01*
X1304342Y37874D01*
X1304849Y38291D01*
X1305165Y38791D01*
X1305229Y39291D01*
X1305102Y39874D01*
X1304659Y40291D01*
X1304215Y40458D01*
X1303645D01*
G01X1304215D02*
X1304595Y40708D01*
X1304912Y41124D01*
X1305039Y41624D01*
X1304912Y42124D01*
X1304595Y42541D01*
X1304025Y42791D01*
X1303455Y42708D01*
X1302885Y42374D01*
G01X1297472Y54583D02*
Y34898D01*
G01X1303772Y35291D02*
X1297472D01*
G01X1291567Y34307D02*
X1297472Y35291D01*
X1291567Y36276D01*
Y34307D01*
G01X1282758Y118197D02*
X1286998Y120847D01*
X1285747Y120961D01*
G01X1282355Y118841D02*
X1283161Y117552D01*
G01X1284357Y124356D02*
G03I-2500J0D01*
G01X1298397Y145002D02*
X1298898Y144519D01*
X1299467Y144308D01*
X1300041Y144355D01*
X1300516Y144551D01*
X1300916Y145070D01*
X1301112Y145629D01*
X1301061Y146130D01*
X1300807Y146670D01*
X1300281Y146976D01*
X1299812Y147039D01*
X1299256Y146911D01*
G01X1299812Y147039D02*
X1300126Y147368D01*
X1300341Y147845D01*
X1300352Y148361D01*
X1300116Y148820D01*
X1299714Y149155D01*
X1299102Y149270D01*
X1298565Y149061D01*
X1298085Y148608D01*
G01X1296364Y145495D02*
G03I-2501J0D01*
G01X1295456Y149711D02*
X1292271Y141280D01*
G01X1292016Y241214D02*
X1292513Y240726D01*
X1293079Y240511D01*
X1293654Y240552D01*
X1294131Y240743D01*
X1294535Y241260D01*
X1294736Y241816D01*
X1294690Y242318D01*
X1294440Y242860D01*
X1293917Y243171D01*
X1293448Y243238D01*
X1292892Y243115D01*
G01X1293448Y243238D02*
X1293765Y243564D01*
X1293985Y244040D01*
X1294000Y244555D01*
X1293768Y245016D01*
X1293369Y245354D01*
X1292759Y245475D01*
X1292220Y245271D01*
X1291736Y244822D01*
G01X1298607Y241478D02*
X1298465Y241532D01*
X1298429Y241695D01*
X1298535Y241803D01*
X1298677Y241749D01*
X1298713Y241587D01*
X1298607Y241478D01*
G01X1303550Y242743D02*
X1302469Y247624D01*
X1301943Y246484D01*
G01X1302808Y242578D02*
X1304292Y242907D01*
G01X1308405Y243817D02*
X1308295Y244902D01*
X1308282Y245838D01*
X1308349Y246707D01*
X1308461Y247670D01*
X1308685Y249000D01*
X1306212Y248453D01*
G01X1311986Y245378D02*
X1312447Y245053D01*
X1312933Y244905D01*
X1313508Y244947D01*
X1314029Y245233D01*
X1314389Y245654D01*
X1314572Y246292D01*
X1314490Y246956D01*
X1314222Y247580D01*
X1313823Y247918D01*
X1313318Y248148D01*
X1312867Y248133D01*
X1312453Y247956D01*
X1311968Y247508D01*
X1311685Y249664D01*
X1313355Y250034D01*
G01X1289986Y241747D02*
G03I-2500J0D01*
G01X1289117Y245949D02*
X1285856Y237546D01*
G01X1309283Y54583D02*
Y34898D01*
G01X1303772Y35291D02*
X1309283D01*
G01X1315189Y36276D02*
X1309283Y35291D01*
X1315189Y34307D01*
Y36276D01*
G01X1417790Y-9197D02*
Y-4197D01*
X1419310D01*
X1419817Y-4447D01*
X1420197Y-5030D01*
X1420324Y-5697D01*
X1420197Y-6364D01*
X1419880Y-6864D01*
X1419310Y-7114D01*
X1417790D01*
G01X1425297Y-9197D02*
Y-5864D01*
G01Y-6447D02*
X1425044Y-6114D01*
X1424664Y-5947D01*
X1424220Y-5864D01*
X1423777Y-6030D01*
X1423397Y-6364D01*
X1423144Y-6864D01*
X1423017Y-7530D01*
X1423144Y-8197D01*
X1423397Y-8697D01*
X1423777Y-9030D01*
X1424220Y-9197D01*
X1424664Y-9114D01*
X1425044Y-8864D01*
X1425297Y-8530D01*
G01X1428180Y-9197D02*
Y-5864D01*
G01Y-6697D02*
X1428434Y-6280D01*
X1428814Y-5947D01*
X1429320Y-5864D01*
X1429764Y-5947D01*
X1430144Y-6280D01*
X1430334Y-6864D01*
Y-9197D01*
G01X1433407Y-6947D02*
X1435434D01*
X1435244Y-6364D01*
X1434927Y-6030D01*
X1434484Y-5864D01*
X1434040Y-5947D01*
X1433660Y-6197D01*
X1433407Y-6780D01*
X1433280Y-7280D01*
Y-7780D01*
X1433407Y-8280D01*
X1433724Y-8780D01*
X1434104Y-9114D01*
X1434547Y-9197D01*
X1434990Y-9030D01*
X1435434Y-8530D01*
G01X1439457Y-9197D02*
Y-4197D01*
G01X1448390Y-9197D02*
Y-4197D01*
X1449974D01*
X1450480Y-4447D01*
X1450797Y-4780D01*
X1450924Y-5447D01*
X1450797Y-6114D01*
X1450417Y-6530D01*
X1449974Y-6780D01*
X1448390D01*
G01X1449974D02*
X1450924Y-9197D01*
G01X1453807Y-6947D02*
X1455834D01*
X1455644Y-6364D01*
X1455327Y-6030D01*
X1454884Y-5864D01*
X1454440Y-5947D01*
X1454060Y-6197D01*
X1453807Y-6780D01*
X1453680Y-7280D01*
Y-7780D01*
X1453807Y-8280D01*
X1454124Y-8780D01*
X1454504Y-9114D01*
X1454947Y-9197D01*
X1455390Y-9030D01*
X1455834Y-8530D01*
G01X1458717Y-5864D02*
X1459857Y-9197D01*
X1460997Y-5864D01*
G01X1470564Y-6530D02*
X1470817Y-6280D01*
X1471007Y-5864D01*
X1471134Y-5280D01*
X1471007Y-4780D01*
X1470754Y-4447D01*
X1470310Y-4197D01*
X1468600D01*
Y-9197D01*
X1470690D01*
X1471134Y-8864D01*
X1471387Y-8364D01*
X1471514Y-7780D01*
X1471387Y-7197D01*
X1471007Y-6697D01*
X1470564Y-6530D01*
X1468600D01*
G01X-320500Y-470483D02*
Y2626000D01*
X2967000D01*
Y-470483D01*
X-320500D01*
G01X-51939Y19685D02*
G03I-6250J0D01*
G01Y619685D02*
G03I-6250J0D01*
G01X-52284Y1279528D02*
G03I-5905J0D01*
G01X-51939Y1307087D02*
G03I-6250J0D01*
G01X-52144Y121792D02*
Y126472D01*
G01Y124132D02*
X-36544D01*
G01Y121792D02*
Y126472D01*
G01X-38624Y137937D02*
X-37324Y139497D01*
X-36544Y141252D01*
Y142812D01*
X-37324Y144372D01*
X-38624Y145542D01*
X-40444Y146127D01*
X-42264Y145737D01*
X-43824Y144762D01*
X-44864Y143007D01*
X-45384Y140667D01*
X-46424Y139302D01*
X-48244Y138717D01*
X-50064Y139107D01*
X-51364Y140082D01*
X-52144Y141447D01*
Y142812D01*
X-51624Y144177D01*
X-50324Y145347D01*
G01X-52144Y159932D02*
X-36544D01*
G01X-52144Y155447D02*
Y164417D01*
G01X-44344Y196902D02*
Y200802D01*
X-39664D01*
X-38104Y199632D01*
X-37064Y198267D01*
X-36544Y196317D01*
X-37064Y194367D01*
X-38104Y193002D01*
X-39664Y191832D01*
X-41484Y191052D01*
X-43564Y190662D01*
X-45384D01*
X-46944Y191052D01*
X-48764Y191832D01*
X-50324Y193002D01*
X-51364Y194172D01*
X-52144Y195732D01*
Y197097D01*
X-51624Y198657D01*
X-50584Y199827D01*
G01X-36544Y217532D02*
Y209732D01*
X-52144D01*
Y217532D01*
G01X-44604Y214412D02*
Y209732D01*
G01X-36544Y227632D02*
X-52144D01*
Y232507D01*
X-51364Y234067D01*
X-50324Y235042D01*
X-48244Y235432D01*
X-46164Y235042D01*
X-44864Y233872D01*
X-44084Y232507D01*
Y227632D01*
G01Y232507D02*
X-36544Y235432D01*
G01X-44864Y250992D02*
X-45644Y251772D01*
X-46944Y252357D01*
X-48764Y252747D01*
X-50324Y252357D01*
X-51364Y251577D01*
X-52144Y250212D01*
Y244947D01*
X-36544D01*
Y251382D01*
X-37584Y252747D01*
X-39144Y253527D01*
X-40964Y253917D01*
X-42784Y253527D01*
X-44344Y252357D01*
X-44864Y250992D01*
Y244947D01*
G01X-36544Y271232D02*
Y263432D01*
X-52144D01*
Y271232D01*
G01X-44604Y268112D02*
Y263432D01*
G01X-36544Y281332D02*
X-52144D01*
Y286207D01*
X-51364Y287767D01*
X-50324Y288742D01*
X-48244Y289132D01*
X-46164Y288742D01*
X-44864Y287572D01*
X-44084Y286207D01*
Y281332D01*
G01Y286207D02*
X-36544Y289132D01*
G01X-31344Y302157D02*
X-33944Y300207D01*
X-36544Y299232D01*
X-46944D01*
X-49544Y300207D01*
X-52144Y302157D01*
G01Y321032D02*
X-36544D01*
G01X-52144Y316547D02*
Y325517D01*
G01Y334057D02*
X-36544Y338932D01*
X-52144Y343807D01*
G01X-36544Y352737D02*
X-52144Y360927D01*
G01Y352737D02*
X-36544Y360927D01*
G01X-52144Y374732D02*
X-51624Y373172D01*
X-50324Y372002D01*
X-48764Y371222D01*
X-46684Y370637D01*
X-44344Y370442D01*
X-42004Y370637D01*
X-39924Y371222D01*
X-38364Y372002D01*
X-37064Y373172D01*
X-36544Y374732D01*
X-37064Y376292D01*
X-38364Y377462D01*
X-39924Y378242D01*
X-42004Y378827D01*
X-44344Y379022D01*
X-46684Y378827D01*
X-48764Y378242D01*
X-50324Y377462D01*
X-51624Y376292D01*
X-52144Y374732D01*
G01X-43044Y388927D02*
X-44864Y390292D01*
X-45904Y391462D01*
X-46424Y393022D01*
X-45904Y394387D01*
X-44864Y395362D01*
X-43304Y396142D01*
X-41484Y396337D01*
X-39924Y396142D01*
X-38364Y395362D01*
X-37064Y394192D01*
X-36544Y392827D01*
X-37064Y391267D01*
X-38624Y389902D01*
X-40964Y389122D01*
X-43564Y388927D01*
X-46944Y389317D01*
X-48764Y389902D01*
X-50584Y390877D01*
X-51884Y392242D01*
X-52144Y393607D01*
X-51624Y394972D01*
X-50324Y395947D01*
G01X-49544Y406827D02*
X-51104Y407997D01*
X-51884Y409362D01*
X-52144Y410922D01*
X-51624Y412872D01*
X-50324Y414237D01*
X-48764Y414627D01*
X-47204Y414432D01*
X-45904Y413652D01*
X-43304Y409752D01*
X-41484Y407997D01*
X-38884Y406827D01*
X-36544Y406437D01*
Y414627D01*
G01X-38364Y425117D02*
X-37064Y426482D01*
X-36544Y428042D01*
X-37064Y429602D01*
X-38624Y430967D01*
X-40964Y431942D01*
X-43304Y432332D01*
X-46164D01*
X-48504Y431942D01*
X-50584Y430967D01*
X-51624Y429797D01*
X-52144Y428432D01*
X-51624Y426872D01*
X-50584Y425702D01*
X-49024Y424922D01*
X-46944Y424532D01*
X-45124Y424922D01*
X-43304Y425897D01*
X-42264Y427067D01*
X-42004Y428432D01*
X-42524Y429992D01*
X-43824Y431162D01*
X-46164Y432332D01*
G01X-36544Y446332D02*
X-36804Y447697D01*
X-37584Y449257D01*
X-38884Y450232D01*
X-40704Y450622D01*
X-42524Y450232D01*
X-44084Y449062D01*
X-44864Y447307D01*
Y445357D01*
X-45384Y444187D01*
X-46684Y443212D01*
X-48504Y442822D01*
X-50324Y443407D01*
X-51624Y444772D01*
X-52144Y446332D01*
X-51624Y447892D01*
X-50324Y449257D01*
X-48504Y449842D01*
X-46684Y449452D01*
X-45384Y448477D01*
X-44864Y447307D01*
Y445357D01*
X-44084Y443602D01*
X-42524Y442432D01*
X-40704Y442042D01*
X-38884Y442432D01*
X-37584Y443407D01*
X-36804Y444967D01*
X-36544Y446332D01*
G01Y459357D02*
X-52144Y464232D01*
X-36544Y469107D01*
G01X-42004Y467352D02*
Y461112D01*
G01X-31344Y483107D02*
X-33944Y485057D01*
X-36544Y486032D01*
X-46944D01*
X-49544Y485057D01*
X-52144Y483107D01*
G01X-52174Y544392D02*
X-52954Y543222D01*
X-53474Y541857D01*
Y540297D01*
X-52694Y538542D01*
X-51394Y537177D01*
X-49834Y536202D01*
X-47234Y535422D01*
X-44894Y535227D01*
X-42554Y535617D01*
X-40994Y536202D01*
X-39434Y537372D01*
X-38394Y538737D01*
X-37874Y540102D01*
Y541467D01*
X-38394Y542832D01*
X-39174Y544002D01*
X-40214Y544977D01*
G01X-46194Y559562D02*
X-46974Y560342D01*
X-48274Y560927D01*
X-50094Y561317D01*
X-51654Y560927D01*
X-52694Y560147D01*
X-53474Y558782D01*
Y553517D01*
X-37874D01*
Y559952D01*
X-38914Y561317D01*
X-40474Y562097D01*
X-42294Y562487D01*
X-44114Y562097D01*
X-45674Y560927D01*
X-46194Y559562D01*
Y553517D01*
G01X331395Y-304184D02*
X330925Y-303869D01*
X330377Y-303659D01*
X329750D01*
X329045Y-303974D01*
X328497Y-304499D01*
X328105Y-305129D01*
X327792Y-306179D01*
X327714Y-307124D01*
X327870Y-308069D01*
X328105Y-308699D01*
X328575Y-309329D01*
X329124Y-309749D01*
X329672Y-309959D01*
X330220D01*
X330769Y-309749D01*
X331239Y-309434D01*
X331630Y-309014D01*
G01X335032Y-303659D02*
X336912D01*
G01X335972D02*
Y-309959D01*
G01X335032D02*
X336912D01*
G01X342272Y-303659D02*
Y-309959D01*
G01X340470Y-303659D02*
X344074D01*
G01X348572Y-309959D02*
Y-307124D01*
X347005Y-303659D01*
G01X350139D02*
X348572Y-307124D01*
G01X359449Y-308699D02*
X359919Y-309434D01*
X360545Y-309854D01*
X361250Y-309959D01*
X361877Y-309854D01*
X362504Y-309329D01*
X362895Y-308699D01*
X362974Y-308069D01*
X362817Y-307334D01*
X362269Y-306809D01*
X361720Y-306599D01*
X361015D01*
G01X361720D02*
X362190Y-306284D01*
X362582Y-305759D01*
X362739Y-305129D01*
X362582Y-304499D01*
X362190Y-303974D01*
X361485Y-303659D01*
X360780Y-303764D01*
X360075Y-304184D01*
G01X365749Y-308699D02*
X366219Y-309434D01*
X366845Y-309854D01*
X367550Y-309959D01*
X368177Y-309854D01*
X368804Y-309329D01*
X369195Y-308699D01*
X369274Y-308069D01*
X369117Y-307334D01*
X368569Y-306809D01*
X368020Y-306599D01*
X367315D01*
G01X368020D02*
X368490Y-306284D01*
X368882Y-305759D01*
X369039Y-305129D01*
X368882Y-304499D01*
X368490Y-303974D01*
X367785Y-303659D01*
X367080Y-303764D01*
X366375Y-304184D01*
G01X372049Y-308699D02*
X372519Y-309434D01*
X373145Y-309854D01*
X373850Y-309959D01*
X374477Y-309854D01*
X375104Y-309329D01*
X375495Y-308699D01*
X375574Y-308069D01*
X375417Y-307334D01*
X374869Y-306809D01*
X374320Y-306599D01*
X373615D01*
G01X374320D02*
X374790Y-306284D01*
X375182Y-305759D01*
X375339Y-305129D01*
X375182Y-304499D01*
X374790Y-303974D01*
X374085Y-303659D01*
X373380Y-303764D01*
X372675Y-304184D01*
G01X379915Y-309959D02*
X380072Y-308594D01*
X380307Y-307439D01*
X380620Y-306389D01*
X381012Y-305234D01*
X381639Y-303659D01*
X378505D01*
G01X386215Y-309959D02*
X386372Y-308594D01*
X386607Y-307439D01*
X386920Y-306389D01*
X387312Y-305234D01*
X387939Y-303659D01*
X384805D01*
G01X392515Y-311114D02*
X392829Y-309749D01*
G01X398972Y-303659D02*
Y-309959D01*
G01X397170Y-303659D02*
X400774D01*
G01X403314Y-309959D02*
X405272Y-303659D01*
X407230Y-309959D01*
G01X406525Y-307754D02*
X404019D01*
G01X410632Y-303659D02*
X412512D01*
G01X411572D02*
Y-309959D01*
G01X410632D02*
X412512D01*
G01X415522Y-303659D02*
X416619Y-309959D01*
X417872Y-303659D01*
X419125Y-309959D01*
X420222Y-303659D01*
G01X422214Y-309959D02*
X424172Y-303659D01*
X426130Y-309959D01*
G01X425425Y-307754D02*
X422919D01*
G01X428670Y-309959D02*
Y-303659D01*
X432274Y-309959D01*
Y-303659D01*
G01X442680Y-312059D02*
X441897Y-311009D01*
X441505Y-309959D01*
Y-305759D01*
X441897Y-304709D01*
X442680Y-303659D01*
G01X454105Y-309959D02*
Y-303659D01*
X456064D01*
X456690Y-303974D01*
X457082Y-304394D01*
X457239Y-305234D01*
X457082Y-306074D01*
X456612Y-306599D01*
X456064Y-306914D01*
X454105D01*
G01X456064D02*
X457239Y-309959D01*
G01X461972Y-310169D02*
X461815Y-310064D01*
Y-309854D01*
X461972Y-309749D01*
X462129Y-309854D01*
Y-310064D01*
X461972Y-310169D01*
G01X468272Y-309959D02*
X467645Y-309854D01*
X467097Y-309434D01*
X466627Y-308804D01*
X466314Y-308069D01*
X466157Y-307229D01*
Y-306389D01*
X466314Y-305549D01*
X466627Y-304814D01*
X467097Y-304184D01*
X467645Y-303764D01*
X468272Y-303659D01*
X468899Y-303764D01*
X469447Y-304184D01*
X469917Y-304814D01*
X470230Y-305549D01*
X470387Y-306389D01*
Y-307229D01*
X470230Y-308069D01*
X469917Y-308804D01*
X469447Y-309434D01*
X468899Y-309854D01*
X468272Y-309959D01*
G01X474572Y-310169D02*
X474415Y-310064D01*
Y-309854D01*
X474572Y-309749D01*
X474729Y-309854D01*
Y-310064D01*
X474572Y-310169D01*
G01X482595Y-304184D02*
X482125Y-303869D01*
X481577Y-303659D01*
X480950D01*
X480245Y-303974D01*
X479697Y-304499D01*
X479305Y-305129D01*
X478992Y-306179D01*
X478914Y-307124D01*
X479070Y-308069D01*
X479305Y-308699D01*
X479775Y-309329D01*
X480324Y-309749D01*
X480872Y-309959D01*
X481420D01*
X481969Y-309749D01*
X482439Y-309434D01*
X482830Y-309014D01*
G01X487172Y-310169D02*
X487015Y-310064D01*
Y-309854D01*
X487172Y-309749D01*
X487329Y-309854D01*
Y-310064D01*
X487172Y-310169D01*
G01X493864Y-312059D02*
X494647Y-311009D01*
X495039Y-309959D01*
Y-305759D01*
X494647Y-304709D01*
X493864Y-303659D01*
G01X330142Y-296809D02*
X331709D01*
Y-298699D01*
X331239Y-299329D01*
X330690Y-299749D01*
X329907Y-299959D01*
X329124Y-299749D01*
X328575Y-299329D01*
X328105Y-298699D01*
X327792Y-297964D01*
X327635Y-297124D01*
Y-296389D01*
X327792Y-295759D01*
X328105Y-295024D01*
X328575Y-294394D01*
X329045Y-293974D01*
X329672Y-293659D01*
X330220D01*
X330847Y-293869D01*
X331317Y-294289D01*
G01X334249Y-293659D02*
Y-298174D01*
X334562Y-299119D01*
X335189Y-299749D01*
X335972Y-299959D01*
X336755Y-299749D01*
X337382Y-299119D01*
X337695Y-298174D01*
Y-293659D01*
G01X341332D02*
X343212D01*
G01X342272D02*
Y-299959D01*
G01X341332D02*
X343212D01*
G01X346927Y-299119D02*
X347554Y-299644D01*
X348259Y-299959D01*
X348885D01*
X349512Y-299644D01*
X349982Y-299119D01*
X350217Y-298384D01*
X350060Y-297649D01*
X349669Y-297019D01*
X348964Y-296599D01*
X348024Y-296389D01*
X347475Y-295969D01*
X347240Y-295234D01*
X347397Y-294499D01*
X347789Y-293974D01*
X348337Y-293659D01*
X348885D01*
X349434Y-293869D01*
X349904Y-294394D01*
G01X353227Y-299959D02*
Y-293659D01*
G01X356517D02*
Y-299959D01*
G01Y-296809D02*
X353227D01*
G01X359214Y-299959D02*
X361172Y-293659D01*
X363130Y-299959D01*
G01X362425Y-297754D02*
X359919D01*
G01X365670Y-299959D02*
Y-293659D01*
X369274Y-299959D01*
Y-293659D01*
G01X378349Y-299959D02*
Y-293659D01*
X379915D01*
X380542Y-293974D01*
X381012Y-294394D01*
X381404Y-295024D01*
X381717Y-295759D01*
X381795Y-296809D01*
X381717Y-297859D01*
X381404Y-298594D01*
X381012Y-299224D01*
X380542Y-299644D01*
X379915Y-299959D01*
X378349D01*
G01X385432Y-293659D02*
X387312D01*
G01X386372D02*
Y-299959D01*
G01X385432D02*
X387312D01*
G01X391027Y-299119D02*
X391654Y-299644D01*
X392359Y-299959D01*
X392985D01*
X393612Y-299644D01*
X394082Y-299119D01*
X394317Y-298384D01*
X394160Y-297649D01*
X393769Y-297019D01*
X393064Y-296599D01*
X392124Y-296389D01*
X391575Y-295969D01*
X391340Y-295234D01*
X391497Y-294499D01*
X391889Y-293974D01*
X392437Y-293659D01*
X392985D01*
X393534Y-293869D01*
X394004Y-294394D01*
G01X398972Y-293659D02*
Y-299959D01*
G01X397170Y-293659D02*
X400774D01*
G01X405272Y-300169D02*
X405115Y-300064D01*
Y-299854D01*
X405272Y-299749D01*
X405429Y-299854D01*
Y-300064D01*
X405272Y-300169D01*
G01X411415Y-301114D02*
X411729Y-299749D01*
G01X417872Y-293659D02*
Y-299959D01*
G01X416070Y-293659D02*
X419674D01*
G01X422214Y-299959D02*
X424172Y-293659D01*
X426130Y-299959D01*
G01X425425Y-297754D02*
X422919D01*
G01X430472Y-299959D02*
X429845Y-299854D01*
X429297Y-299434D01*
X428827Y-298804D01*
X428514Y-298069D01*
X428357Y-297229D01*
Y-296389D01*
X428514Y-295549D01*
X428827Y-294814D01*
X429297Y-294184D01*
X429845Y-293764D01*
X430472Y-293659D01*
X431099Y-293764D01*
X431647Y-294184D01*
X432117Y-294814D01*
X432430Y-295549D01*
X432587Y-296389D01*
Y-297229D01*
X432430Y-298069D01*
X432117Y-298804D01*
X431647Y-299434D01*
X431099Y-299854D01*
X430472Y-299959D01*
G01X436772D02*
Y-297124D01*
X435205Y-293659D01*
G01X438339D02*
X436772Y-297124D01*
G01X441349Y-293659D02*
Y-298174D01*
X441662Y-299119D01*
X442289Y-299749D01*
X443072Y-299959D01*
X443855Y-299749D01*
X444482Y-299119D01*
X444795Y-298174D01*
Y-293659D01*
G01X447414Y-299959D02*
X449372Y-293659D01*
X451330Y-299959D01*
G01X450625Y-297754D02*
X448119D01*
G01X453870Y-299959D02*
Y-293659D01*
X457474Y-299959D01*
Y-293659D01*
G01X327870Y-289959D02*
Y-283659D01*
X331474Y-289959D01*
Y-283659D01*
G01X335972Y-289959D02*
X335345Y-289854D01*
X334797Y-289434D01*
X334327Y-288804D01*
X334014Y-288069D01*
X333857Y-287229D01*
Y-286389D01*
X334014Y-285549D01*
X334327Y-284814D01*
X334797Y-284184D01*
X335345Y-283764D01*
X335972Y-283659D01*
X336599Y-283764D01*
X337147Y-284184D01*
X337617Y-284814D01*
X337930Y-285549D01*
X338087Y-286389D01*
Y-287229D01*
X337930Y-288069D01*
X337617Y-288804D01*
X337147Y-289434D01*
X336599Y-289854D01*
X335972Y-289959D01*
G01X342272Y-290169D02*
X342115Y-290064D01*
Y-289854D01*
X342272Y-289749D01*
X342429Y-289854D01*
Y-290064D01*
X342272Y-290169D01*
G01X347084Y-284709D02*
X347554Y-284079D01*
X348102Y-283764D01*
X348729Y-283659D01*
X349512Y-283869D01*
X350060Y-284394D01*
X350217Y-285024D01*
X350139Y-285654D01*
X349825Y-286179D01*
X348259Y-287229D01*
X347554Y-287964D01*
X347084Y-289014D01*
X346927Y-289959D01*
X350217D01*
G01X354872D02*
Y-283659D01*
X353932Y-284919D01*
G01Y-289959D02*
X355812D01*
G01X361172D02*
Y-283659D01*
X360232Y-284919D01*
G01Y-289959D02*
X362112D01*
G01X367315Y-291114D02*
X367629Y-289749D01*
G01X371422Y-283659D02*
X372519Y-289959D01*
X373772Y-283659D01*
X375025Y-289959D01*
X376122Y-283659D01*
G01X381639Y-289959D02*
X378505D01*
Y-283659D01*
X381639D01*
G01X380385Y-286704D02*
X378505D01*
G01X384570Y-289959D02*
Y-283659D01*
X388174Y-289959D01*
Y-283659D01*
G01X391027Y-289959D02*
Y-283659D01*
G01X394317D02*
Y-289959D01*
G01Y-286809D02*
X391027D01*
G01X397249Y-283659D02*
Y-288174D01*
X397562Y-289119D01*
X398189Y-289749D01*
X398972Y-289959D01*
X399755Y-289749D01*
X400382Y-289119D01*
X400695Y-288174D01*
Y-283659D01*
G01X403314Y-289959D02*
X405272Y-283659D01*
X407230Y-289959D01*
G01X406525Y-287754D02*
X404019D01*
G01X416384Y-284709D02*
X416854Y-284079D01*
X417402Y-283764D01*
X418029Y-283659D01*
X418812Y-283869D01*
X419360Y-284394D01*
X419517Y-285024D01*
X419439Y-285654D01*
X419125Y-286179D01*
X417559Y-287229D01*
X416854Y-287964D01*
X416384Y-289014D01*
X416227Y-289959D01*
X419517D01*
G01X422370D02*
Y-283659D01*
X425974Y-289959D01*
Y-283659D01*
G01X428749Y-289959D02*
Y-283659D01*
X430315D01*
X430942Y-283974D01*
X431412Y-284394D01*
X431804Y-285024D01*
X432117Y-285759D01*
X432195Y-286809D01*
X432117Y-287859D01*
X431804Y-288594D01*
X431412Y-289224D01*
X430942Y-289644D01*
X430315Y-289959D01*
X428749D01*
G01X441505D02*
Y-283659D01*
X443464D01*
X444090Y-283974D01*
X444482Y-284394D01*
X444639Y-285234D01*
X444482Y-286074D01*
X444012Y-286599D01*
X443464Y-286914D01*
X441505D01*
G01X443464D02*
X444639Y-289959D01*
G01X447649D02*
Y-283659D01*
X449215D01*
X449842Y-283974D01*
X450312Y-284394D01*
X450704Y-285024D01*
X451017Y-285759D01*
X451095Y-286809D01*
X451017Y-287859D01*
X450704Y-288594D01*
X450312Y-289224D01*
X449842Y-289644D01*
X449215Y-289959D01*
X447649D01*
G01X455672Y-290169D02*
X455515Y-290064D01*
Y-289854D01*
X455672Y-289749D01*
X455829Y-289854D01*
Y-290064D01*
X455672Y-290169D01*
G01X351972Y-279259D02*
X349452Y-278842D01*
X347247Y-277176D01*
X345357Y-274676D01*
X344097Y-271759D01*
X343467Y-268426D01*
Y-265092D01*
X344097Y-261759D01*
X345357Y-258842D01*
X347247Y-256343D01*
X349452Y-254676D01*
X351972Y-254259D01*
X354492Y-254676D01*
X356697Y-256343D01*
X358587Y-258842D01*
X359847Y-261759D01*
X360477Y-265092D01*
Y-268426D01*
X359847Y-271759D01*
X358587Y-274676D01*
X356697Y-277176D01*
X354492Y-278842D01*
X351972Y-279259D01*
G01X354492Y-272592D02*
X358272Y-279259D01*
G01X371817Y-262593D02*
Y-274259D01*
X373077Y-277176D01*
X374967Y-278842D01*
X377172Y-279259D01*
X379377Y-278842D01*
X381267Y-277176D01*
X382527Y-274259D01*
G01Y-279259D02*
Y-262593D01*
G01X408042Y-279259D02*
Y-262593D01*
G01Y-265509D02*
X406782Y-263843D01*
X404892Y-263009D01*
X402687Y-262593D01*
X400482Y-263426D01*
X398592Y-265092D01*
X397332Y-267593D01*
X396702Y-270926D01*
X397332Y-274259D01*
X398592Y-276760D01*
X400482Y-278426D01*
X402687Y-279259D01*
X404892Y-278842D01*
X406782Y-277593D01*
X408042Y-275926D01*
G01X422217Y-279259D02*
Y-262593D01*
G01Y-266759D02*
X423477Y-264676D01*
X425367Y-263009D01*
X427887Y-262593D01*
X430092Y-263009D01*
X431982Y-264676D01*
X432927Y-267593D01*
Y-279259D01*
G01X452772Y-254259D02*
Y-279259D01*
G01X448362Y-262593D02*
X457182D01*
G01X483642Y-279259D02*
Y-262593D01*
G01Y-265509D02*
X482382Y-263843D01*
X480492Y-263009D01*
X478287Y-262593D01*
X476082Y-263426D01*
X474192Y-265092D01*
X472932Y-267593D01*
X472302Y-270926D01*
X472932Y-274259D01*
X474192Y-276760D01*
X476082Y-278426D01*
X478287Y-279259D01*
X480492Y-278842D01*
X482382Y-277593D01*
X483642Y-275926D01*
G01X392055Y1430667D02*
X392985Y1431916D01*
X394070Y1432542D01*
X395310Y1432750D01*
X396860Y1432333D01*
X397945Y1431292D01*
X398255Y1430042D01*
X398100Y1428791D01*
X397480Y1427750D01*
X394380Y1425667D01*
X392985Y1424208D01*
X392055Y1422125D01*
X391745Y1420250D01*
X398255D01*
G01X409260D02*
Y1432750D01*
X403525Y1423792D01*
X411275D01*
G01X421660Y1420250D02*
Y1432750D01*
X415925Y1423792D01*
X423675D01*
G01X432200Y1419833D02*
X431890Y1420042D01*
Y1420458D01*
X432200Y1420667D01*
X432510Y1420458D01*
Y1420042D01*
X432200Y1419833D01*
G01X441190Y1422125D02*
X442120Y1421083D01*
X443205Y1420458D01*
X444600Y1420250D01*
X445995Y1420667D01*
X447080Y1421500D01*
X447855Y1422958D01*
X448010Y1424625D01*
X447700Y1426292D01*
X446925Y1427333D01*
X445840Y1428167D01*
X444755Y1428375D01*
X443670Y1428167D01*
X442275Y1427333D01*
X442740Y1432750D01*
X446925D01*
G01X457000Y1420250D02*
X458085Y1420458D01*
X459325Y1421083D01*
X460100Y1422125D01*
X460410Y1423583D01*
X460100Y1425041D01*
X459170Y1426292D01*
X457775Y1426917D01*
X456225D01*
X455295Y1427333D01*
X454520Y1428375D01*
X454210Y1429833D01*
X454675Y1431292D01*
X455760Y1432333D01*
X457000Y1432750D01*
X458240Y1432333D01*
X459325Y1431292D01*
X459790Y1429833D01*
X459480Y1428375D01*
X458705Y1427333D01*
X457775Y1426917D01*
X456225D01*
X454830Y1426292D01*
X453900Y1425041D01*
X453590Y1423583D01*
X453900Y1422125D01*
X454675Y1421083D01*
X455915Y1420458D01*
X457000Y1420250D01*
G01X386015Y1446708D02*
X387100Y1445667D01*
X388340Y1445250D01*
X389580Y1445667D01*
X390665Y1446916D01*
X391440Y1448792D01*
X391750Y1450667D01*
Y1452958D01*
X391440Y1454833D01*
X390665Y1456500D01*
X389735Y1457333D01*
X388650Y1457750D01*
X387410Y1457333D01*
X386480Y1456500D01*
X385860Y1455250D01*
X385550Y1453583D01*
X385860Y1452125D01*
X386635Y1450667D01*
X387565Y1449833D01*
X388650Y1449625D01*
X389890Y1450041D01*
X390820Y1451083D01*
X391750Y1452958D01*
G01X398105Y1450458D02*
X399190Y1451917D01*
X400120Y1452750D01*
X401360Y1453167D01*
X402445Y1452750D01*
X403220Y1451917D01*
X403840Y1450667D01*
X403995Y1449208D01*
X403840Y1447958D01*
X403220Y1446708D01*
X402290Y1445667D01*
X401205Y1445250D01*
X399965Y1445667D01*
X398880Y1446916D01*
X398260Y1448792D01*
X398105Y1450875D01*
X398415Y1453583D01*
X398880Y1455042D01*
X399655Y1456500D01*
X400740Y1457542D01*
X401825Y1457750D01*
X402910Y1457333D01*
X403685Y1456292D01*
G01X410505Y1455667D02*
X411435Y1456916D01*
X412520Y1457542D01*
X413760Y1457750D01*
X415310Y1457333D01*
X416395Y1456292D01*
X416705Y1455042D01*
X416550Y1453791D01*
X415930Y1452750D01*
X412830Y1450667D01*
X411435Y1449208D01*
X410505Y1447125D01*
X410195Y1445250D01*
X416705D01*
G01X423215Y1446708D02*
X424300Y1445667D01*
X425540Y1445250D01*
X426780Y1445667D01*
X427865Y1446916D01*
X428640Y1448792D01*
X428950Y1450667D01*
Y1452958D01*
X428640Y1454833D01*
X427865Y1456500D01*
X426935Y1457333D01*
X425850Y1457750D01*
X424610Y1457333D01*
X423680Y1456500D01*
X423060Y1455250D01*
X422750Y1453583D01*
X423060Y1452125D01*
X423835Y1450667D01*
X424765Y1449833D01*
X425850Y1449625D01*
X427090Y1450041D01*
X428020Y1451083D01*
X428950Y1452958D01*
G01X438250Y1444833D02*
X437940Y1445042D01*
Y1445458D01*
X438250Y1445667D01*
X438560Y1445458D01*
Y1445042D01*
X438250Y1444833D01*
G01X450650Y1445250D02*
Y1457750D01*
X448790Y1455250D01*
G01Y1445250D02*
X452510D01*
G01X460105Y1455667D02*
X461035Y1456916D01*
X462120Y1457542D01*
X463360Y1457750D01*
X464910Y1457333D01*
X465995Y1456292D01*
X466305Y1455042D01*
X466150Y1453791D01*
X465530Y1452750D01*
X462430Y1450667D01*
X461035Y1449208D01*
X460105Y1447125D01*
X459795Y1445250D01*
X466305D01*
G01X523322Y-258959D02*
Y-266959D01*
X527322D01*
G01X535122D02*
Y-261626D01*
G01Y-262559D02*
X534722Y-262026D01*
X534122Y-261759D01*
X533422Y-261626D01*
X532722Y-261892D01*
X532122Y-262426D01*
X531722Y-263226D01*
X531522Y-264292D01*
X531722Y-265359D01*
X532122Y-266159D01*
X532722Y-266692D01*
X533422Y-266959D01*
X534122Y-266826D01*
X534722Y-266426D01*
X535122Y-265893D01*
G01X539222Y-269359D02*
X539822Y-269626D01*
X540622Y-269359D01*
X541122Y-268826D01*
X541522Y-268159D01*
X542122Y-266026D01*
X543422Y-261626D01*
G01X540222D02*
X542122Y-266026D01*
G01X547822Y-263359D02*
X551022D01*
X550722Y-262426D01*
X550222Y-261892D01*
X549522Y-261626D01*
X548822Y-261759D01*
X548222Y-262159D01*
X547822Y-263092D01*
X547622Y-263893D01*
Y-264692D01*
X547822Y-265492D01*
X548322Y-266292D01*
X548922Y-266826D01*
X549622Y-266959D01*
X550322Y-266692D01*
X551022Y-265893D01*
G01X555922Y-266959D02*
Y-261626D01*
G01Y-262692D02*
X556422Y-262159D01*
X556922Y-261759D01*
X557622Y-261626D01*
X558122Y-261759D01*
X558722Y-262159D01*
G01X542022Y-316959D02*
Y-308959D01*
X546622Y-316959D01*
Y-308959D01*
G01X552322Y-311626D02*
Y-316959D01*
G01Y-309492D02*
X552122Y-309359D01*
Y-309092D01*
X552322Y-308959D01*
X552522Y-309092D01*
Y-309359D01*
X552322Y-309492D01*
G01X558622Y-316959D02*
Y-311626D01*
G01Y-312959D02*
X559022Y-312292D01*
X559622Y-311759D01*
X560422Y-311626D01*
X561122Y-311759D01*
X561722Y-312292D01*
X562022Y-313226D01*
Y-316959D01*
G01X570122D02*
Y-311626D01*
G01Y-312559D02*
X569722Y-312026D01*
X569122Y-311759D01*
X568422Y-311626D01*
X567722Y-311892D01*
X567122Y-312426D01*
X566722Y-313226D01*
X566522Y-314292D01*
X566722Y-315359D01*
X567122Y-316159D01*
X567722Y-316692D01*
X568422Y-316959D01*
X569122Y-316826D01*
X569722Y-316426D01*
X570122Y-315893D01*
G01X542322Y-291959D02*
Y-283959D01*
X544722D01*
X545522Y-284359D01*
X546122Y-285292D01*
X546322Y-286359D01*
X546122Y-287426D01*
X545622Y-288226D01*
X544722Y-288626D01*
X542322D01*
G01X549822Y-291959D02*
X552322Y-283959D01*
X554822Y-291959D01*
G01X553922Y-289159D02*
X550722D01*
G01X558022Y-291959D02*
Y-283959D01*
X562622Y-291959D01*
Y-283959D01*
G01X570322Y-291959D02*
X566322D01*
Y-283959D01*
X570322D01*
G01X568722Y-287826D02*
X566322D01*
G01X574322Y-283959D02*
Y-291959D01*
X578322D01*
G01X649922Y-310292D02*
X650522Y-309492D01*
X651222Y-309092D01*
X652022Y-308959D01*
X653022Y-309226D01*
X653722Y-309892D01*
X653922Y-310692D01*
X653822Y-311493D01*
X653422Y-312159D01*
X651422Y-313492D01*
X650522Y-314426D01*
X649922Y-315759D01*
X649722Y-316959D01*
X653922D01*
G01X659822Y-308959D02*
X659022Y-309226D01*
X658422Y-309892D01*
X658022Y-310692D01*
X657722Y-311759D01*
X657622Y-312959D01*
X657722Y-314159D01*
X658022Y-315226D01*
X658422Y-316026D01*
X659022Y-316692D01*
X659822Y-316959D01*
X660622Y-316692D01*
X661222Y-316026D01*
X661622Y-315226D01*
X661922Y-314159D01*
X662022Y-312959D01*
X661922Y-311759D01*
X661622Y-310692D01*
X661222Y-309892D01*
X660622Y-309226D01*
X659822Y-308959D01*
G01X665922Y-310292D02*
X666522Y-309492D01*
X667222Y-309092D01*
X668022Y-308959D01*
X669022Y-309226D01*
X669722Y-309892D01*
X669922Y-310692D01*
X669822Y-311493D01*
X669422Y-312159D01*
X667422Y-313492D01*
X666522Y-314426D01*
X665922Y-315759D01*
X665722Y-316959D01*
X669922D01*
G01X673922Y-310292D02*
X674522Y-309492D01*
X675222Y-309092D01*
X676022Y-308959D01*
X677022Y-309226D01*
X677722Y-309892D01*
X677922Y-310692D01*
X677822Y-311493D01*
X677422Y-312159D01*
X675422Y-313492D01*
X674522Y-314426D01*
X673922Y-315759D01*
X673722Y-316959D01*
X677922D01*
G01X682022Y-317226D02*
X685622Y-308959D01*
G01X691822Y-316959D02*
Y-308959D01*
X690622Y-310559D01*
G01Y-316959D02*
X693022D01*
G01X697922Y-310292D02*
X698522Y-309492D01*
X699222Y-309092D01*
X700022Y-308959D01*
X701022Y-309226D01*
X701722Y-309892D01*
X701922Y-310692D01*
X701822Y-311493D01*
X701422Y-312159D01*
X699422Y-313492D01*
X698522Y-314426D01*
X697922Y-315759D01*
X697722Y-316959D01*
X701922D01*
G01X706022Y-317226D02*
X709622Y-308959D01*
G01X715822D02*
X715022Y-309226D01*
X714422Y-309892D01*
X714022Y-310692D01*
X713722Y-311759D01*
X713622Y-312959D01*
X713722Y-314159D01*
X714022Y-315226D01*
X714422Y-316026D01*
X715022Y-316692D01*
X715822Y-316959D01*
X716622Y-316692D01*
X717222Y-316026D01*
X717622Y-315226D01*
X717922Y-314159D01*
X718022Y-312959D01*
X717922Y-311759D01*
X717622Y-310692D01*
X717222Y-309892D01*
X716622Y-309226D01*
X715822Y-308959D01*
G01X722122Y-316026D02*
X722822Y-316692D01*
X723622Y-316959D01*
X724422Y-316692D01*
X725122Y-315893D01*
X725622Y-314692D01*
X725822Y-313492D01*
Y-312026D01*
X725622Y-310826D01*
X725122Y-309759D01*
X724522Y-309226D01*
X723822Y-308959D01*
X723022Y-309226D01*
X722422Y-309759D01*
X722022Y-310559D01*
X721822Y-311626D01*
X722022Y-312559D01*
X722522Y-313492D01*
X723122Y-314026D01*
X723822Y-314159D01*
X724622Y-313893D01*
X725222Y-313226D01*
X725822Y-312026D01*
G01X649622Y-291959D02*
Y-283959D01*
X651622D01*
X652422Y-284359D01*
X653022Y-284892D01*
X653522Y-285692D01*
X653922Y-286626D01*
X654022Y-287959D01*
X653922Y-289292D01*
X653522Y-290226D01*
X653022Y-291026D01*
X652422Y-291559D01*
X651622Y-291959D01*
X649622D01*
G01X657322D02*
X659822Y-283959D01*
X662322Y-291959D01*
G01X661422Y-289159D02*
X658222D01*
G01X667822Y-283959D02*
X667022Y-284226D01*
X666422Y-284892D01*
X666022Y-285692D01*
X665722Y-286759D01*
X665622Y-287959D01*
X665722Y-289159D01*
X666022Y-290226D01*
X666422Y-291026D01*
X667022Y-291692D01*
X667822Y-291959D01*
X668622Y-291692D01*
X669222Y-291026D01*
X669622Y-290226D01*
X669922Y-289159D01*
X670022Y-287959D01*
X669922Y-286759D01*
X669622Y-285692D01*
X669222Y-284892D01*
X668622Y-284226D01*
X667822Y-283959D01*
G01X673922Y-291959D02*
Y-283959D01*
X677722D01*
G01X676322Y-287826D02*
X673922D01*
G01X683822Y-283959D02*
X683022Y-284226D01*
X682422Y-284892D01*
X682022Y-285692D01*
X681722Y-286759D01*
X681622Y-287959D01*
X681722Y-289159D01*
X682022Y-290226D01*
X682422Y-291026D01*
X683022Y-291692D01*
X683822Y-291959D01*
X684622Y-291692D01*
X685222Y-291026D01*
X685622Y-290226D01*
X685922Y-289159D01*
X686022Y-287959D01*
X685922Y-286759D01*
X685622Y-285692D01*
X685222Y-284892D01*
X684622Y-284226D01*
X683822Y-283959D01*
G01X691822D02*
Y-291959D01*
G01X689522Y-283959D02*
X694122D01*
G01X697922Y-291959D02*
Y-283959D01*
X701722D01*
G01X700322Y-287826D02*
X697922D01*
G01X708622Y-287692D02*
X709022Y-287292D01*
X709322Y-286626D01*
X709522Y-285692D01*
X709322Y-284892D01*
X708922Y-284359D01*
X708222Y-283959D01*
X705522D01*
Y-291959D01*
X708822D01*
X709522Y-291426D01*
X709922Y-290626D01*
X710122Y-289692D01*
X709922Y-288759D01*
X709322Y-287959D01*
X708622Y-287692D01*
X705522D01*
G01X713922Y-288626D02*
X714622Y-287692D01*
X715222Y-287159D01*
X716022Y-286892D01*
X716722Y-287159D01*
X717222Y-287692D01*
X717622Y-288492D01*
X717722Y-289426D01*
X717622Y-290226D01*
X717222Y-291026D01*
X716622Y-291692D01*
X715922Y-291959D01*
X715122Y-291692D01*
X714422Y-290893D01*
X714022Y-289692D01*
X713922Y-288359D01*
X714122Y-286626D01*
X714422Y-285692D01*
X714922Y-284759D01*
X715622Y-284092D01*
X716322Y-283959D01*
X717022Y-284226D01*
X717522Y-284892D01*
G01X721622Y-291959D02*
Y-283959D01*
X723622D01*
X724422Y-284359D01*
X725022Y-284892D01*
X725522Y-285692D01*
X725922Y-286626D01*
X726022Y-287959D01*
X725922Y-289292D01*
X725522Y-290226D01*
X725022Y-291026D01*
X724422Y-291559D01*
X723622Y-291959D01*
X721622D01*
G01X731822Y-283959D02*
X731022Y-284226D01*
X730422Y-284892D01*
X730022Y-285692D01*
X729722Y-286759D01*
X729622Y-287959D01*
X729722Y-289159D01*
X730022Y-290226D01*
X730422Y-291026D01*
X731022Y-291692D01*
X731822Y-291959D01*
X732622Y-291692D01*
X733222Y-291026D01*
X733622Y-290226D01*
X733922Y-289159D01*
X734022Y-287959D01*
X733922Y-286759D01*
X733622Y-285692D01*
X733222Y-284892D01*
X732622Y-284226D01*
X731822Y-283959D01*
G01X649862Y-270000D02*
Y-263700D01*
X652838D01*
G01X651742Y-266745D02*
X649862D01*
G01X657650Y-263700D02*
X657023Y-263910D01*
X656553Y-264435D01*
X656240Y-265065D01*
X656005Y-265905D01*
X655927Y-266850D01*
X656005Y-267795D01*
X656240Y-268635D01*
X656553Y-269265D01*
X657023Y-269790D01*
X657650Y-270000D01*
X658277Y-269790D01*
X658747Y-269265D01*
X659060Y-268635D01*
X659295Y-267795D01*
X659373Y-266850D01*
X659295Y-265905D01*
X659060Y-265065D01*
X658747Y-264435D01*
X658277Y-263910D01*
X657650Y-263700D01*
G01X663950D02*
Y-270000D01*
G01X662148Y-263700D02*
X665752D01*
G01X667900Y-272100D02*
X672600D01*
G01X674983Y-270000D02*
Y-263700D01*
X676863D01*
X677490Y-264015D01*
X677960Y-264750D01*
X678117Y-265590D01*
X677960Y-266430D01*
X677568Y-267060D01*
X676863Y-267375D01*
X674983D01*
G01X684573Y-264225D02*
X684103Y-263910D01*
X683555Y-263700D01*
X682928D01*
X682223Y-264015D01*
X681675Y-264540D01*
X681283Y-265170D01*
X680970Y-266220D01*
X680892Y-267165D01*
X681048Y-268110D01*
X681283Y-268740D01*
X681753Y-269370D01*
X682302Y-269790D01*
X682850Y-270000D01*
X683398D01*
X683947Y-269790D01*
X684417Y-269475D01*
X684808Y-269055D01*
G01X689777Y-266640D02*
X690090Y-266325D01*
X690325Y-265800D01*
X690482Y-265065D01*
X690325Y-264435D01*
X690012Y-264015D01*
X689463Y-263700D01*
X687348D01*
Y-270000D01*
X689933D01*
X690482Y-269580D01*
X690795Y-268950D01*
X690952Y-268215D01*
X690795Y-267480D01*
X690325Y-266850D01*
X689777Y-266640D01*
X687348D01*
G01X693100Y-272100D02*
X697800D01*
G01X700262Y-270000D02*
Y-263700D01*
X703238D01*
G01X702142Y-266745D02*
X700262D01*
G01X706092Y-270000D02*
X708050Y-263700D01*
X710008Y-270000D01*
G01X709303Y-267795D02*
X706797D01*
G01X712548Y-270000D02*
Y-263700D01*
X716152Y-270000D01*
Y-263700D01*
G01X718300Y-272100D02*
X723000D01*
G01X727577Y-266640D02*
X727890Y-266325D01*
X728125Y-265800D01*
X728282Y-265065D01*
X728125Y-264435D01*
X727812Y-264015D01*
X727263Y-263700D01*
X725148D01*
Y-270000D01*
X727733D01*
X728282Y-269580D01*
X728595Y-268950D01*
X728752Y-268215D01*
X728595Y-267480D01*
X728125Y-266850D01*
X727577Y-266640D01*
X725148D01*
G01X733250Y-270000D02*
X732623Y-269895D01*
X732075Y-269475D01*
X731605Y-268845D01*
X731292Y-268110D01*
X731135Y-267270D01*
Y-266430D01*
X731292Y-265590D01*
X731605Y-264855D01*
X732075Y-264225D01*
X732623Y-263805D01*
X733250Y-263700D01*
X733877Y-263805D01*
X734425Y-264225D01*
X734895Y-264855D01*
X735208Y-265590D01*
X735365Y-266430D01*
Y-267270D01*
X735208Y-268110D01*
X734895Y-268845D01*
X734425Y-269475D01*
X733877Y-269895D01*
X733250Y-270000D01*
G01X737592D02*
X739550Y-263700D01*
X741508Y-270000D01*
G01X740803Y-267795D02*
X738297D01*
G01X744283Y-270000D02*
Y-263700D01*
X746242D01*
X746868Y-264015D01*
X747260Y-264435D01*
X747417Y-265275D01*
X747260Y-266115D01*
X746790Y-266640D01*
X746242Y-266955D01*
X744283D01*
G01X746242D02*
X747417Y-270000D01*
G01X750427D02*
Y-263700D01*
X751993D01*
X752620Y-264015D01*
X753090Y-264435D01*
X753482Y-265065D01*
X753795Y-265800D01*
X753873Y-266850D01*
X753795Y-267900D01*
X753482Y-268635D01*
X753090Y-269265D01*
X752620Y-269685D01*
X751993Y-270000D01*
X750427D01*
G01X756100Y-272100D02*
X760800D01*
G01X762713Y-270000D02*
Y-263700D01*
X764750Y-268950D01*
X766787Y-263700D01*
Y-270000D01*
G01X769483D02*
Y-263700D01*
X771363D01*
X771990Y-264015D01*
X772460Y-264750D01*
X772617Y-265590D01*
X772460Y-266430D01*
X772068Y-267060D01*
X771363Y-267375D01*
X769483D01*
G01X775627Y-269055D02*
X776097Y-269580D01*
X776645Y-269895D01*
X777350Y-270000D01*
X778055Y-269790D01*
X778603Y-269370D01*
X778995Y-268635D01*
X779073Y-267795D01*
X778917Y-266955D01*
X778525Y-266430D01*
X777977Y-266010D01*
X777428Y-265905D01*
X776880Y-266010D01*
X776175Y-266430D01*
X776410Y-263700D01*
X778525D01*
G01X783650D02*
X783023Y-263910D01*
X782553Y-264435D01*
X782240Y-265065D01*
X782005Y-265905D01*
X781927Y-266850D01*
X782005Y-267795D01*
X782240Y-268635D01*
X782553Y-269265D01*
X783023Y-269790D01*
X783650Y-270000D01*
X784277Y-269790D01*
X784747Y-269265D01*
X785060Y-268635D01*
X785295Y-267795D01*
X785373Y-266850D01*
X785295Y-265905D01*
X785060Y-265065D01*
X784747Y-264435D01*
X784277Y-263910D01*
X783650Y-263700D01*
G01X790890Y-270000D02*
Y-263700D01*
X787992Y-268215D01*
X791908D01*
G01X796250Y-270000D02*
X796798Y-269895D01*
X797425Y-269580D01*
X797817Y-269055D01*
X797973Y-268320D01*
X797817Y-267585D01*
X797347Y-266955D01*
X796642Y-266640D01*
X795858D01*
X795388Y-266430D01*
X794997Y-265905D01*
X794840Y-265170D01*
X795075Y-264435D01*
X795623Y-263910D01*
X796250Y-263700D01*
X796877Y-263910D01*
X797425Y-264435D01*
X797660Y-265170D01*
X797503Y-265905D01*
X797112Y-266430D01*
X796642Y-266640D01*
X795858D01*
X795153Y-266955D01*
X794683Y-267585D01*
X794527Y-268320D01*
X794683Y-269055D01*
X795075Y-269580D01*
X795702Y-269895D01*
X796250Y-270000D01*
G01X738322Y-319959D02*
Y-311959D01*
X737122Y-313559D01*
G01Y-319959D02*
X739522D01*
G01X744422Y-316626D02*
X745122Y-315692D01*
X745722Y-315159D01*
X746522Y-314892D01*
X747222Y-315159D01*
X747722Y-315692D01*
X748122Y-316492D01*
X748222Y-317426D01*
X748122Y-318226D01*
X747722Y-319026D01*
X747122Y-319692D01*
X746422Y-319959D01*
X745622Y-319692D01*
X744922Y-318893D01*
X744522Y-317692D01*
X744422Y-316359D01*
X744622Y-314626D01*
X744922Y-313692D01*
X745422Y-312759D01*
X746122Y-312092D01*
X746822Y-311959D01*
X747522Y-312226D01*
X748022Y-312892D01*
G01X754322Y-320226D02*
X754122Y-320092D01*
Y-319826D01*
X754322Y-319692D01*
X754522Y-319826D01*
Y-320092D01*
X754322Y-320226D01*
G01X760422Y-316626D02*
X761122Y-315692D01*
X761722Y-315159D01*
X762522Y-314892D01*
X763222Y-315159D01*
X763722Y-315692D01*
X764122Y-316492D01*
X764222Y-317426D01*
X764122Y-318226D01*
X763722Y-319026D01*
X763122Y-319692D01*
X762422Y-319959D01*
X761622Y-319692D01*
X760922Y-318893D01*
X760522Y-317692D01*
X760422Y-316359D01*
X760622Y-314626D01*
X760922Y-313692D01*
X761422Y-312759D01*
X762122Y-312092D01*
X762822Y-311959D01*
X763522Y-312226D01*
X764022Y-312892D01*
G01X783322Y-319959D02*
Y-311959D01*
X782122Y-313559D01*
G01Y-319959D02*
X784522D01*
G01X791122D02*
X791322Y-318226D01*
X791622Y-316759D01*
X792022Y-315426D01*
X792522Y-313959D01*
X793322Y-311959D01*
X789322D01*
G01X799322Y-320226D02*
X799122Y-320092D01*
Y-319826D01*
X799322Y-319692D01*
X799522Y-319826D01*
Y-320092D01*
X799322Y-320226D01*
G01X805422Y-313292D02*
X806022Y-312492D01*
X806722Y-312092D01*
X807522Y-311959D01*
X808522Y-312226D01*
X809222Y-312892D01*
X809422Y-313692D01*
X809322Y-314493D01*
X808922Y-315159D01*
X806922Y-316492D01*
X806022Y-317426D01*
X805422Y-318759D01*
X805222Y-319959D01*
X809422D01*
G01X803122Y-294959D02*
Y-286959D01*
X805122D01*
X805922Y-287359D01*
X806522Y-287892D01*
X807022Y-288692D01*
X807422Y-289626D01*
X807522Y-290959D01*
X807422Y-292292D01*
X807022Y-293226D01*
X806522Y-294026D01*
X805922Y-294559D01*
X805122Y-294959D01*
X803122D01*
G01X871603Y19685D02*
G03I-6250J0D01*
G01X871259Y66929D02*
G03I-5906J0D01*
G01X871603Y1307087D02*
G03I-6250J0D01*
G01X985250Y637100D02*
X972750D01*
X975250Y635240D01*
G01X985250D02*
Y638960D01*
G01X982750Y646090D02*
X984209Y647020D01*
X985042Y648260D01*
X985250Y649655D01*
X985042Y650895D01*
X984000Y652135D01*
X982750Y652910D01*
X981500Y653065D01*
X980042Y652755D01*
X979000Y651670D01*
X978583Y650585D01*
Y649190D01*
G01Y650585D02*
X977958Y651515D01*
X976917Y652290D01*
X975667Y652600D01*
X974417Y652290D01*
X973375Y651515D01*
X972750Y650120D01*
X972958Y648725D01*
X973792Y647330D01*
G01X974833Y658955D02*
X973584Y659885D01*
X972958Y660970D01*
X972750Y662210D01*
X973167Y663760D01*
X974208Y664845D01*
X975458Y665155D01*
X976709Y665000D01*
X977750Y664380D01*
X979833Y661280D01*
X981292Y659885D01*
X983375Y658955D01*
X985250Y658645D01*
Y665155D01*
G01X980042Y671355D02*
X978583Y672440D01*
X977750Y673370D01*
X977333Y674610D01*
X977750Y675695D01*
X978583Y676470D01*
X979833Y677090D01*
X981292Y677245D01*
X982542Y677090D01*
X983792Y676470D01*
X984833Y675540D01*
X985250Y674455D01*
X984833Y673215D01*
X983584Y672130D01*
X981708Y671510D01*
X979625Y671355D01*
X976917Y671665D01*
X975458Y672130D01*
X974000Y672905D01*
X972958Y673990D01*
X972750Y675075D01*
X973167Y676160D01*
X974208Y676935D01*
G01X985250Y686390D02*
X982542Y686700D01*
X980250Y687165D01*
X978167Y687785D01*
X975875Y688560D01*
X972750Y689800D01*
Y683600D01*
G01X985667Y699100D02*
X985458Y698790D01*
X985042D01*
X984833Y699100D01*
X985042Y699410D01*
X985458D01*
X985667Y699100D01*
G01X985250Y711190D02*
X982542Y711500D01*
X980250Y711965D01*
X978167Y712585D01*
X975875Y713360D01*
X972750Y714600D01*
Y708400D01*
G01X974833Y720955D02*
X973584Y721885D01*
X972958Y722970D01*
X972750Y724210D01*
X973167Y725760D01*
X974208Y726845D01*
X975458Y727155D01*
X976709Y727000D01*
X977750Y726380D01*
X979833Y723280D01*
X981292Y721885D01*
X983375Y720955D01*
X985250Y720645D01*
Y727155D01*
G01X1007750Y664840D02*
X1009209Y665770D01*
X1010042Y667010D01*
X1010250Y668405D01*
X1010042Y669645D01*
X1009000Y670885D01*
X1007750Y671660D01*
X1006500Y671815D01*
X1005042Y671505D01*
X1004000Y670420D01*
X1003583Y669335D01*
Y667940D01*
G01Y669335D02*
X1002958Y670265D01*
X1001917Y671040D01*
X1000667Y671350D01*
X999417Y671040D01*
X998375Y670265D01*
X997750Y668870D01*
X997958Y667475D01*
X998792Y666080D01*
G01X1007750Y677240D02*
X1009209Y678170D01*
X1010042Y679410D01*
X1010250Y680805D01*
X1010042Y682045D01*
X1009000Y683285D01*
X1007750Y684060D01*
X1006500Y684215D01*
X1005042Y683905D01*
X1004000Y682820D01*
X1003583Y681735D01*
Y680340D01*
G01Y681735D02*
X1002958Y682665D01*
X1001917Y683440D01*
X1000667Y683750D01*
X999417Y683440D01*
X998375Y682665D01*
X997750Y681270D01*
X997958Y679875D01*
X998792Y678480D01*
G01X1010250Y692740D02*
X1007542Y693050D01*
X1005250Y693515D01*
X1003167Y694135D01*
X1000875Y694910D01*
X997750Y696150D01*
Y689950D01*
G01X1228575Y285535D02*
X1472984D01*
Y1520D01*
X1228575D01*
Y285535D01*
G01X1275819Y134110D02*
G03I-5906J0D01*
G01X1275612Y232613D02*
G03I-6250J0D01*
G01X1284087Y60882D02*
X1293535D01*
G02Y53008I0J-3937D01*
G01X1284087D01*
G01X1313220Y60882D02*
G03Y53008I0J-3937D01*
G01X1322669D01*
G01X1313220Y60882D02*
X1322669D01*
M02*
